FILE_TYPE = MACRO_DRAWING;
SET COLOR_WIRE YELLOW;
SET COLOR_PROP ORANGE;
SET COLOR_DOT WHITE;
SET COLOR_ARC YELLOW;
SET COLOR_BODY GREEN;
SET COLOR_NOTE PURPLE;
SET PROP_DISPLAY VALUE;
SET PAGE_NUMBER P43;
FORCEADD GENOA_SP5..7
(-4700 3675);
FORCEPROP 1 LAST LOCATION U26
J 0
(-5345 6506);
DISPLAY 0.489362 (-5345 6506);
PAINT SKYBLUE (-5345 6506);
FORCEPROP 0 LAST $SEC 7
J 0
(-5325 6550);
DISPLAY 0.680851 (-5325 6550);
PAINT MONO (-5325 6550);
DISPLAY INVISIBLE (-5325 6550);
FORCEPROP 0 LAST CDS_SEC 7
J 0
(-5350 6475);
DISPLAY 1.021277 (-5350 6475);
DISPLAY INVISIBLE (-5350 6475);
FORCEPROP 0 LASTPIN (-5500 3050) $PN BC2
J 2
(-5510 3060);
DISPLAY 0.489362 (-5510 3060);
PAINT MONO (-5510 3060);
FORCEPROP 0 LASTPIN (-5500 3000) $PN BD2
J 2
(-5510 3010);
DISPLAY 0.489362 (-5510 3010);
PAINT MONO (-5510 3010);
FORCEPROP 0 LASTPIN (-5500 1900) $PN BF2
J 2
(-5510 1910);
DISPLAY 0.489362 (-5510 1910);
PAINT MONO (-5510 1910);
FORCEPROP 0 LASTPIN (-5500 1850) $PN BG2
J 2
(-5510 1860);
DISPLAY 0.489362 (-5510 1860);
PAINT MONO (-5510 1860);
FORCEPROP 0 LASTPIN (-5500 2200) $PN AR2
J 2
(-5510 2210);
DISPLAY 0.489362 (-5510 2210);
PAINT MONO (-5510 2210);
FORCEPROP 0 LASTPIN (-5500 2100) $PN AT2
J 2
(-5510 2110);
DISPLAY 0.489362 (-5510 2110);
PAINT MONO (-5510 2110);
FORCEPROP 0 LASTPIN (-5500 2900) $PN AU2
J 2
(-5510 2910);
DISPLAY 0.489362 (-5510 2910);
PAINT MONO (-5510 2910);
FORCEPROP 0 LASTPIN (-5500 2850) $PN AV4
J 2
(-5510 2860);
DISPLAY 0.489362 (-5510 2860);
PAINT MONO (-5510 2860);
FORCEPROP 0 LASTPIN (-5500 2750) $PN BN3
J 2
(-5510 2760);
DISPLAY 0.489362 (-5510 2760);
PAINT MONO (-5510 2760);
FORCEPROP 0 LASTPIN (-5500 1750) $PN AV2
J 2
(-5510 1760);
DISPLAY 0.489362 (-5510 1760);
PAINT MONO (-5510 1760);
FORCEPROP 0 LASTPIN (-5500 1700) $PN AW3
J 2
(-5510 1710);
DISPLAY 0.489362 (-5510 1710);
PAINT MONO (-5510 1710);
FORCEPROP 0 LASTPIN (-5500 1600) $PN BP4
J 2
(-5510 1610);
DISPLAY 0.489362 (-5510 1610);
PAINT MONO (-5510 1610);
FORCEPROP 0 LASTPIN (-5500 3900) $PN AW2
J 2
(-5510 3910);
DISPLAY 0.489362 (-5510 3910);
PAINT MONO (-5510 3910);
FORCEPROP 0 LASTPIN (-5500 3850) $PN AY2
J 2
(-5510 3860);
DISPLAY 0.489362 (-5510 3860);
PAINT MONO (-5510 3860);
FORCEPROP 0 LASTPIN (-5500 3800) $PN AY4
J 2
(-5510 3810);
DISPLAY 0.489362 (-5510 3810);
PAINT MONO (-5510 3810);
FORCEPROP 0 LASTPIN (-5500 3750) $PN BA3
J 2
(-5510 3760);
DISPLAY 0.489362 (-5510 3760);
PAINT MONO (-5510 3760);
FORCEPROP 0 LASTPIN (-5500 3700) $PN BA2
J 2
(-5510 3710);
DISPLAY 0.489362 (-5510 3710);
PAINT MONO (-5510 3710);
FORCEPROP 0 LASTPIN (-5500 3650) $PN BB2
J 2
(-5510 3660);
DISPLAY 0.489362 (-5510 3660);
PAINT MONO (-5510 3660);
FORCEPROP 0 LASTPIN (-5500 3600) $PN BB4
J 2
(-5510 3610);
DISPLAY 0.489362 (-5510 3610);
PAINT MONO (-5510 3610);
FORCEPROP 0 LASTPIN (-3900 2450) $PN AJ2
J 0
(-3890 2460);
DISPLAY 0.489362 (-3890 2460);
PAINT MONO (-3890 2460);
FORCEPROP 0 LASTPIN (-3900 2400) $PN AK4
J 0
(-3890 2410);
DISPLAY 0.489362 (-3890 2410);
PAINT MONO (-3890 2410);
FORCEPROP 0 LASTPIN (-3900 2350) $PN AK2
J 0
(-3890 2360);
DISPLAY 0.489362 (-3890 2360);
PAINT MONO (-3890 2360);
FORCEPROP 0 LASTPIN (-3900 2300) $PN AL3
J 0
(-3890 2310);
DISPLAY 0.489362 (-3890 2310);
PAINT MONO (-3890 2310);
FORCEPROP 0 LASTPIN (-3900 2250) $PN AN2
J 0
(-3890 2260);
DISPLAY 0.489362 (-3890 2260);
PAINT MONO (-3890 2260);
FORCEPROP 0 LASTPIN (-3900 2200) $PN AP4
J 0
(-3890 2210);
DISPLAY 0.489362 (-3890 2210);
PAINT MONO (-3890 2210);
FORCEPROP 0 LASTPIN (-3900 2150) $PN AP2
J 0
(-3890 2160);
DISPLAY 0.489362 (-3890 2160);
PAINT MONO (-3890 2160);
FORCEPROP 0 LASTPIN (-3900 2100) $PN AR3
J 0
(-3890 2110);
DISPLAY 0.489362 (-3890 2110);
PAINT MONO (-3890 2110);
FORCEPROP 0 LASTPIN (-3900 6050) $PN E2
J 0
(-3890 6060);
DISPLAY 0.489362 (-3890 6060);
PAINT MONO (-3890 6060);
FORCEPROP 0 LASTPIN (-3900 6000) $PN F4
J 0
(-3890 6010);
DISPLAY 0.489362 (-3890 6010);
PAINT MONO (-3890 6010);
FORCEPROP 0 LASTPIN (-3900 5950) $PN F2
J 0
(-3890 5960);
DISPLAY 0.489362 (-3890 5960);
PAINT MONO (-3890 5960);
FORCEPROP 0 LASTPIN (-3900 5900) $PN G3
J 0
(-3890 5910);
DISPLAY 0.489362 (-3890 5910);
PAINT MONO (-3890 5910);
FORCEPROP 0 LASTPIN (-3900 5850) $PN J2
J 0
(-3890 5860);
DISPLAY 0.489362 (-3890 5860);
PAINT MONO (-3890 5860);
FORCEPROP 0 LASTPIN (-3900 5800) $PN K4
J 0
(-3890 5810);
DISPLAY 0.489362 (-3890 5810);
PAINT MONO (-3890 5810);
FORCEPROP 0 LASTPIN (-3900 5750) $PN K2
J 0
(-3890 5760);
DISPLAY 0.489362 (-3890 5760);
PAINT MONO (-3890 5760);
FORCEPROP 0 LASTPIN (-3900 5700) $PN L3
J 0
(-3890 5710);
DISPLAY 0.489362 (-3890 5710);
PAINT MONO (-3890 5710);
FORCEPROP 0 LASTPIN (-3900 5600) $PN L2
J 0
(-3890 5610);
DISPLAY 0.489362 (-3890 5610);
PAINT MONO (-3890 5610);
FORCEPROP 0 LASTPIN (-3900 5550) $PN M4
J 0
(-3890 5560);
DISPLAY 0.489362 (-3890 5560);
PAINT MONO (-3890 5560);
FORCEPROP 0 LASTPIN (-3900 5500) $PN M2
J 0
(-3890 5510);
DISPLAY 0.489362 (-3890 5510);
PAINT MONO (-3890 5510);
FORCEPROP 0 LASTPIN (-3900 5450) $PN N3
J 0
(-3890 5460);
DISPLAY 0.489362 (-3890 5460);
PAINT MONO (-3890 5460);
FORCEPROP 0 LASTPIN (-3900 5400) $PN R2
J 0
(-3890 5410);
DISPLAY 0.489362 (-3890 5410);
PAINT MONO (-3890 5410);
FORCEPROP 0 LASTPIN (-3900 5350) $PN T4
J 0
(-3890 5360);
DISPLAY 0.489362 (-3890 5360);
PAINT MONO (-3890 5360);
FORCEPROP 0 LASTPIN (-3900 5300) $PN T2
J 0
(-3890 5310);
DISPLAY 0.489362 (-3890 5310);
PAINT MONO (-3890 5310);
FORCEPROP 0 LASTPIN (-3900 5250) $PN U3
J 0
(-3890 5260);
DISPLAY 0.489362 (-3890 5260);
PAINT MONO (-3890 5260);
FORCEPROP 0 LASTPIN (-3900 5150) $PN U2
J 0
(-3890 5160);
DISPLAY 0.489362 (-3890 5160);
PAINT MONO (-3890 5160);
FORCEPROP 0 LASTPIN (-3900 5100) $PN V4
J 0
(-3890 5110);
DISPLAY 0.489362 (-3890 5110);
PAINT MONO (-3890 5110);
FORCEPROP 0 LASTPIN (-3900 5050) $PN V2
J 0
(-3890 5060);
DISPLAY 0.489362 (-3890 5060);
PAINT MONO (-3890 5060);
FORCEPROP 0 LASTPIN (-3900 5000) $PN W3
J 0
(-3890 5010);
DISPLAY 0.489362 (-3890 5010);
PAINT MONO (-3890 5010);
FORCEPROP 0 LASTPIN (-3900 4950) $PN AA2
J 0
(-3890 4960);
DISPLAY 0.489362 (-3890 4960);
PAINT MONO (-3890 4960);
FORCEPROP 0 LASTPIN (-3900 4900) $PN AB4
J 0
(-3890 4910);
DISPLAY 0.489362 (-3890 4910);
PAINT MONO (-3890 4910);
FORCEPROP 0 LASTPIN (-3900 4850) $PN AB2
J 0
(-3890 4860);
DISPLAY 0.489362 (-3890 4860);
PAINT MONO (-3890 4860);
FORCEPROP 0 LASTPIN (-3900 4800) $PN AC3
J 0
(-3890 4810);
DISPLAY 0.489362 (-3890 4810);
PAINT MONO (-3890 4810);
FORCEPROP 0 LASTPIN (-3900 4700) $PN AC2
J 0
(-3890 4710);
DISPLAY 0.489362 (-3890 4710);
PAINT MONO (-3890 4710);
FORCEPROP 0 LASTPIN (-3900 4650) $PN AD4
J 0
(-3890 4660);
DISPLAY 0.489362 (-3890 4660);
PAINT MONO (-3890 4660);
FORCEPROP 0 LASTPIN (-3900 4600) $PN AD2
J 0
(-3890 4610);
DISPLAY 0.489362 (-3890 4610);
PAINT MONO (-3890 4610);
FORCEPROP 0 LASTPIN (-3900 4550) $PN AE3
J 0
(-3890 4560);
DISPLAY 0.489362 (-3890 4560);
PAINT MONO (-3890 4560);
FORCEPROP 0 LASTPIN (-3900 4500) $PN AG2
J 0
(-3890 4510);
DISPLAY 0.489362 (-3890 4510);
PAINT MONO (-3890 4510);
FORCEPROP 0 LASTPIN (-3900 4450) $PN AH4
J 0
(-3890 4460);
DISPLAY 0.489362 (-3890 4460);
PAINT MONO (-3890 4460);
FORCEPROP 0 LASTPIN (-3900 4400) $PN AH2
J 0
(-3890 4410);
DISPLAY 0.489362 (-3890 4410);
PAINT MONO (-3890 4410);
FORCEPROP 0 LASTPIN (-3900 4350) $PN AJ3
J 0
(-3890 4360);
DISPLAY 0.489362 (-3890 4360);
PAINT MONO (-3890 4360);
FORCEPROP 0 LASTPIN (-5500 6050) $PN G2
J 2
(-5510 6060);
DISPLAY 0.489362 (-5510 6060);
PAINT MONO (-5510 6060);
FORCEPROP 0 LASTPIN (-5500 5950) $PN N2
J 2
(-5510 5960);
DISPLAY 0.489362 (-5510 5960);
PAINT MONO (-5510 5960);
FORCEPROP 0 LASTPIN (-5500 5850) $PN W2
J 2
(-5510 5860);
DISPLAY 0.489362 (-5510 5860);
PAINT MONO (-5510 5860);
FORCEPROP 0 LASTPIN (-5500 5750) $PN AE2
J 2
(-5510 5760);
DISPLAY 0.489362 (-5510 5760);
PAINT MONO (-5510 5760);
FORCEPROP 0 LASTPIN (-5500 5650) $PN AL2
J 2
(-5510 5660);
DISPLAY 0.489362 (-5510 5660);
PAINT MONO (-5510 5660);
FORCEPROP 0 LASTPIN (-5500 5550) $PN J3
J 2
(-5510 5560);
DISPLAY 0.489362 (-5510 5560);
PAINT MONO (-5510 5560);
FORCEPROP 0 LASTPIN (-5500 5450) $PN R3
J 2
(-5510 5460);
DISPLAY 0.489362 (-5510 5460);
PAINT MONO (-5510 5460);
FORCEPROP 0 LASTPIN (-5500 5350) $PN AA3
J 2
(-5510 5360);
DISPLAY 0.489362 (-5510 5360);
PAINT MONO (-5510 5360);
FORCEPROP 0 LASTPIN (-5500 5250) $PN AG3
J 2
(-5510 5260);
DISPLAY 0.489362 (-5510 5260);
PAINT MONO (-5510 5260);
FORCEPROP 0 LASTPIN (-5500 5150) $PN AN3
J 2
(-5510 5160);
DISPLAY 0.489362 (-5510 5160);
PAINT MONO (-5510 5160);
FORCEPROP 0 LASTPIN (-5500 6000) $PN H2
J 2
(-5510 6010);
DISPLAY 0.489362 (-5510 6010);
PAINT MONO (-5510 6010);
FORCEPROP 0 LASTPIN (-5500 5900) $PN P2
J 2
(-5510 5910);
DISPLAY 0.489362 (-5510 5910);
PAINT MONO (-5510 5910);
FORCEPROP 0 LASTPIN (-5500 5800) $PN Y2
J 2
(-5510 5810);
DISPLAY 0.489362 (-5510 5810);
PAINT MONO (-5510 5810);
FORCEPROP 0 LASTPIN (-5500 5700) $PN AF2
J 2
(-5510 5710);
DISPLAY 0.489362 (-5510 5710);
PAINT MONO (-5510 5710);
FORCEPROP 0 LASTPIN (-5500 5600) $PN AM2
J 2
(-5510 5610);
DISPLAY 0.489362 (-5510 5610);
PAINT MONO (-5510 5610);
FORCEPROP 0 LASTPIN (-5500 5500) $PN H4
J 2
(-5510 5510);
DISPLAY 0.489362 (-5510 5510);
PAINT MONO (-5510 5510);
FORCEPROP 0 LASTPIN (-5500 5400) $PN P4
J 2
(-5510 5410);
DISPLAY 0.489362 (-5510 5410);
PAINT MONO (-5510 5410);
FORCEPROP 0 LASTPIN (-5500 5300) $PN Y4
J 2
(-5510 5310);
DISPLAY 0.489362 (-5510 5310);
PAINT MONO (-5510 5310);
FORCEPROP 0 LASTPIN (-5500 5200) $PN AF4
J 2
(-5510 5210);
DISPLAY 0.489362 (-5510 5210);
PAINT MONO (-5510 5210);
FORCEPROP 0 LASTPIN (-5500 5100) $PN AM4
J 2
(-5510 5110);
DISPLAY 0.489362 (-5510 5110);
PAINT MONO (-5510 5110);
FORCEPROP 0 LASTPIN (-5500 2650) $PN BC3
J 2
(-5510 2660);
DISPLAY 0.489362 (-5510 2660);
PAINT MONO (-5510 2660);
FORCEPROP 0 LASTPIN (-5500 2550) $PN BM4
J 2
(-5510 2560);
DISPLAY 0.489362 (-5510 2560);
PAINT MONO (-5510 2560);
FORCEPROP 0 LASTPIN (-5500 2500) $PN BN2
J 2
(-5510 2510);
DISPLAY 0.489362 (-5510 2510);
PAINT MONO (-5510 2510);
FORCEPROP 0 LASTPIN (-5500 2400) $PN BP2
J 2
(-5510 2410);
DISPLAY 0.489362 (-5510 2410);
PAINT MONO (-5510 2410);
FORCEPROP 0 LASTPIN (-5500 1500) $PN BL2
J 2
(-5510 1510);
DISPLAY 0.489362 (-5510 1510);
PAINT MONO (-5510 1510);
FORCEPROP 0 LASTPIN (-5500 1450) $PN BM2
J 2
(-5510 1460);
DISPLAY 0.489362 (-5510 1460);
PAINT MONO (-5510 1460);
FORCEPROP 0 LASTPIN (-5500 1350) $PN BR2
J 2
(-5510 1360);
DISPLAY 0.489362 (-5510 1360);
PAINT MONO (-5510 1360);
FORCEPROP 0 LASTPIN (-5500 3500) $PN BG3
J 2
(-5510 3510);
DISPLAY 0.489362 (-5510 3510);
PAINT MONO (-5510 3510);
FORCEPROP 0 LASTPIN (-5500 3450) $PN BH4
J 2
(-5510 3460);
DISPLAY 0.489362 (-5510 3460);
PAINT MONO (-5510 3460);
FORCEPROP 0 LASTPIN (-5500 3400) $PN BH2
J 2
(-5510 3410);
DISPLAY 0.489362 (-5510 3410);
PAINT MONO (-5510 3410);
FORCEPROP 0 LASTPIN (-5500 3350) $PN BJ2
J 2
(-5510 3360);
DISPLAY 0.489362 (-5510 3360);
PAINT MONO (-5510 3360);
FORCEPROP 0 LASTPIN (-5500 3300) $PN BJ3
J 2
(-5510 3310);
DISPLAY 0.489362 (-5510 3310);
PAINT MONO (-5510 3310);
FORCEPROP 0 LASTPIN (-5500 3250) $PN BK4
J 2
(-5510 3260);
DISPLAY 0.489362 (-5510 3260);
PAINT MONO (-5510 3260);
FORCEPROP 0 LASTPIN (-5500 3200) $PN BK2
J 2
(-5510 3210);
DISPLAY 0.489362 (-5510 3210);
PAINT MONO (-5510 3210);
FORCEPROP 0 LASTPIN (-3900 2000) $PN BY2
J 0
(-3890 2010);
DISPLAY 0.489362 (-3890 2010);
PAINT MONO (-3890 2010);
FORCEPROP 0 LASTPIN (-3900 1950) $PN CA3
J 0
(-3890 1960);
DISPLAY 0.489362 (-3890 1960);
PAINT MONO (-3890 1960);
FORCEPROP 0 LASTPIN (-3900 1900) $PN CA2
J 0
(-3890 1910);
DISPLAY 0.489362 (-3890 1910);
PAINT MONO (-3890 1910);
FORCEPROP 0 LASTPIN (-3900 1850) $PN CB4
J 0
(-3890 1860);
DISPLAY 0.489362 (-3890 1860);
PAINT MONO (-3890 1860);
FORCEPROP 0 LASTPIN (-3900 1800) $PN BT2
J 0
(-3890 1810);
DISPLAY 0.489362 (-3890 1810);
PAINT MONO (-3890 1810);
FORCEPROP 0 LASTPIN (-3900 1750) $PN BU3
J 0
(-3890 1760);
DISPLAY 0.489362 (-3890 1760);
PAINT MONO (-3890 1760);
FORCEPROP 0 LASTPIN (-3900 1700) $PN BU2
J 0
(-3890 1710);
DISPLAY 0.489362 (-3890 1710);
PAINT MONO (-3890 1710);
FORCEPROP 0 LASTPIN (-3900 1650) $PN BV4
J 0
(-3890 1660);
DISPLAY 0.489362 (-3890 1660);
PAINT MONO (-3890 1660);
FORCEPROP 0 LASTPIN (-3900 4250) $PN CB2
J 0
(-3890 4260);
DISPLAY 0.489362 (-3890 4260);
PAINT MONO (-3890 4260);
FORCEPROP 0 LASTPIN (-3900 4200) $PN CC3
J 0
(-3890 4210);
DISPLAY 0.489362 (-3890 4210);
PAINT MONO (-3890 4210);
FORCEPROP 0 LASTPIN (-3900 4150) $PN CC2
J 0
(-3890 4160);
DISPLAY 0.489362 (-3890 4160);
PAINT MONO (-3890 4160);
FORCEPROP 0 LASTPIN (-3900 4100) $PN CD4
J 0
(-3890 4110);
DISPLAY 0.489362 (-3890 4110);
PAINT MONO (-3890 4110);
FORCEPROP 0 LASTPIN (-3900 4050) $PN CF2
J 0
(-3890 4060);
DISPLAY 0.489362 (-3890 4060);
PAINT MONO (-3890 4060);
FORCEPROP 0 LASTPIN (-3900 4000) $PN CG3
J 0
(-3890 4010);
DISPLAY 0.489362 (-3890 4010);
PAINT MONO (-3890 4010);
FORCEPROP 0 LASTPIN (-3900 3950) $PN CG2
J 0
(-3890 3960);
DISPLAY 0.489362 (-3890 3960);
PAINT MONO (-3890 3960);
FORCEPROP 0 LASTPIN (-3900 3900) $PN CH4
J 0
(-3890 3910);
DISPLAY 0.489362 (-3890 3910);
PAINT MONO (-3890 3910);
FORCEPROP 0 LASTPIN (-3900 3800) $PN CH2
J 0
(-3890 3810);
DISPLAY 0.489362 (-3890 3810);
PAINT MONO (-3890 3810);
FORCEPROP 0 LASTPIN (-3900 3750) $PN CJ3
J 0
(-3890 3760);
DISPLAY 0.489362 (-3890 3760);
PAINT MONO (-3890 3760);
FORCEPROP 0 LASTPIN (-3900 3700) $PN CJ2
J 0
(-3890 3710);
DISPLAY 0.489362 (-3890 3710);
PAINT MONO (-3890 3710);
FORCEPROP 0 LASTPIN (-3900 3650) $PN CK4
J 0
(-3890 3660);
DISPLAY 0.489362 (-3890 3660);
PAINT MONO (-3890 3660);
FORCEPROP 0 LASTPIN (-3900 3600) $PN CM2
J 0
(-3890 3610);
DISPLAY 0.489362 (-3890 3610);
PAINT MONO (-3890 3610);
FORCEPROP 0 LASTPIN (-3900 3550) $PN CN3
J 0
(-3890 3560);
DISPLAY 0.489362 (-3890 3560);
PAINT MONO (-3890 3560);
FORCEPROP 0 LASTPIN (-3900 3500) $PN CN2
J 0
(-3890 3510);
DISPLAY 0.489362 (-3890 3510);
PAINT MONO (-3890 3510);
FORCEPROP 0 LASTPIN (-3900 3450) $PN CP4
J 0
(-3890 3460);
DISPLAY 0.489362 (-3890 3460);
PAINT MONO (-3890 3460);
FORCEPROP 0 LASTPIN (-3900 3350) $PN CP2
J 0
(-3890 3360);
DISPLAY 0.489362 (-3890 3360);
PAINT MONO (-3890 3360);
FORCEPROP 0 LASTPIN (-3900 3300) $PN CR3
J 0
(-3890 3310);
DISPLAY 0.489362 (-3890 3310);
PAINT MONO (-3890 3310);
FORCEPROP 0 LASTPIN (-3900 3250) $PN CR2
J 0
(-3890 3260);
DISPLAY 0.489362 (-3890 3260);
PAINT MONO (-3890 3260);
FORCEPROP 0 LASTPIN (-3900 3200) $PN CT4
J 0
(-3890 3210);
DISPLAY 0.489362 (-3890 3210);
PAINT MONO (-3890 3210);
FORCEPROP 0 LASTPIN (-3900 3150) $PN CV2
J 0
(-3890 3160);
DISPLAY 0.489362 (-3890 3160);
PAINT MONO (-3890 3160);
FORCEPROP 0 LASTPIN (-3900 3100) $PN CW3
J 0
(-3890 3110);
DISPLAY 0.489362 (-3890 3110);
PAINT MONO (-3890 3110);
FORCEPROP 0 LASTPIN (-3900 3050) $PN CW2
J 0
(-3890 3060);
DISPLAY 0.489362 (-3890 3060);
PAINT MONO (-3890 3060);
FORCEPROP 0 LASTPIN (-3900 3000) $PN CY4
J 0
(-3890 3010);
DISPLAY 0.489362 (-3890 3010);
PAINT MONO (-3890 3010);
FORCEPROP 0 LASTPIN (-3900 2900) $PN CY2
J 0
(-3890 2910);
DISPLAY 0.489362 (-3890 2910);
PAINT MONO (-3890 2910);
FORCEPROP 0 LASTPIN (-3900 2850) $PN DA3
J 0
(-3890 2860);
DISPLAY 0.489362 (-3890 2860);
PAINT MONO (-3890 2860);
FORCEPROP 0 LASTPIN (-3900 2800) $PN DA2
J 0
(-3890 2810);
DISPLAY 0.489362 (-3890 2810);
PAINT MONO (-3890 2810);
FORCEPROP 0 LASTPIN (-3900 2750) $PN DB4
J 0
(-3890 2760);
DISPLAY 0.489362 (-3890 2760);
PAINT MONO (-3890 2760);
FORCEPROP 0 LASTPIN (-3900 2700) $PN DD2
J 0
(-3890 2710);
DISPLAY 0.489362 (-3890 2710);
PAINT MONO (-3890 2710);
FORCEPROP 0 LASTPIN (-3900 2650) $PN DE3
J 0
(-3890 2660);
DISPLAY 0.489362 (-3890 2660);
PAINT MONO (-3890 2660);
FORCEPROP 0 LASTPIN (-3900 2600) $PN DE2
J 0
(-3890 2610);
DISPLAY 0.489362 (-3890 2610);
PAINT MONO (-3890 2610);
FORCEPROP 0 LASTPIN (-3900 2550) $PN DF2
J 0
(-3890 2560);
DISPLAY 0.489362 (-3890 2560);
PAINT MONO (-3890 2560);
FORCEPROP 0 LASTPIN (-5500 5000) $PN CD2
J 2
(-5510 5010);
DISPLAY 0.489362 (-5510 5010);
PAINT MONO (-5510 5010);
FORCEPROP 0 LASTPIN (-5500 4900) $PN CK2
J 2
(-5510 4910);
DISPLAY 0.489362 (-5510 4910);
PAINT MONO (-5510 4910);
FORCEPROP 0 LASTPIN (-5500 4800) $PN CT2
J 2
(-5510 4810);
DISPLAY 0.489362 (-5510 4810);
PAINT MONO (-5510 4810);
FORCEPROP 0 LASTPIN (-5500 4700) $PN DB2
J 2
(-5510 4710);
DISPLAY 0.489362 (-5510 4710);
PAINT MONO (-5510 4710);
FORCEPROP 0 LASTPIN (-5500 4600) $PN BY4
J 2
(-5510 4610);
DISPLAY 0.489362 (-5510 4610);
PAINT MONO (-5510 4610);
FORCEPROP 0 LASTPIN (-5500 4500) $PN CF4
J 2
(-5510 4510);
DISPLAY 0.489362 (-5510 4510);
PAINT MONO (-5510 4510);
FORCEPROP 0 LASTPIN (-5500 4400) $PN CM4
J 2
(-5510 4410);
DISPLAY 0.489362 (-5510 4410);
PAINT MONO (-5510 4410);
FORCEPROP 0 LASTPIN (-5500 4300) $PN CV4
J 2
(-5510 4310);
DISPLAY 0.489362 (-5510 4310);
PAINT MONO (-5510 4310);
FORCEPROP 0 LASTPIN (-5500 4200) $PN DD4
J 2
(-5510 4210);
DISPLAY 0.489362 (-5510 4210);
PAINT MONO (-5510 4210);
FORCEPROP 0 LASTPIN (-5500 4100) $PN BV2
J 2
(-5510 4110);
DISPLAY 0.489362 (-5510 4110);
PAINT MONO (-5510 4110);
FORCEPROP 0 LASTPIN (-5500 4950) $PN CE2
J 2
(-5510 4960);
DISPLAY 0.489362 (-5510 4960);
PAINT MONO (-5510 4960);
FORCEPROP 0 LASTPIN (-5500 4850) $PN CL2
J 2
(-5510 4860);
DISPLAY 0.489362 (-5510 4860);
PAINT MONO (-5510 4860);
FORCEPROP 0 LASTPIN (-5500 4750) $PN CU2
J 2
(-5510 4760);
DISPLAY 0.489362 (-5510 4760);
PAINT MONO (-5510 4760);
FORCEPROP 0 LASTPIN (-5500 4650) $PN DC2
J 2
(-5510 4660);
DISPLAY 0.489362 (-5510 4660);
PAINT MONO (-5510 4660);
FORCEPROP 0 LASTPIN (-5500 4550) $PN BW3
J 2
(-5510 4560);
DISPLAY 0.489362 (-5510 4560);
PAINT MONO (-5510 4560);
FORCEPROP 0 LASTPIN (-5500 4450) $PN CE3
J 2
(-5510 4460);
DISPLAY 0.489362 (-5510 4460);
PAINT MONO (-5510 4460);
FORCEPROP 0 LASTPIN (-5500 4350) $PN CL3
J 2
(-5510 4360);
DISPLAY 0.489362 (-5510 4360);
PAINT MONO (-5510 4360);
FORCEPROP 0 LASTPIN (-5500 4250) $PN CU3
J 2
(-5510 4260);
DISPLAY 0.489362 (-5510 4260);
PAINT MONO (-5510 4260);
FORCEPROP 0 LASTPIN (-5500 4150) $PN DC3
J 2
(-5510 4160);
DISPLAY 0.489362 (-5510 4160);
PAINT MONO (-5510 4160);
FORCEPROP 0 LASTPIN (-5500 4050) $PN BW2
J 2
(-5510 4060);
DISPLAY 0.489362 (-5510 4060);
PAINT MONO (-5510 4060);
FORCEPROP 0 LASTPIN (-5500 2300) $PN BL3
J 2
(-5510 2310);
DISPLAY 0.489362 (-5510 2310);
PAINT MONO (-5510 2310);
FORCEPROP 0 LASTPIN (-5500 1250) $PN BF4
J 2
(-5510 1260);
DISPLAY 0.489362 (-5510 1260);
PAINT MONO (-5510 1260);
FORCEPROP 2 LAST PART_TYPE SMLF
J 0
(-5350 6425);
DISPLAY 1.021277 (-5350 6425);
FORCEPROP 1 LAST MATERIAL IO
J 0
(-5345 6232);
DISPLAY 0.489362 (-5345 6232);
PAINT SKYBLUE (-5345 6232);
FORCEPROP 2 LAST VALUE SOCKET6096_13568-001
J 0
(-5350 6325);
DISPLAY 0.489362 (-5350 6325);
PAINT SKYBLUE (-5350 6325);
FORCEPROP 1 LAST PART_NUMBER DGA^6000030
J 0
(-5345 6359);
DISPLAY 0.489362 (-5345 6359);
PAINT SKYBLUE (-5345 6359);
FORCEPROP 1 LAST NEEDS_NO_SIZE TRUE
J 0
(-4700 3675);
DISPLAY 0.723404 (-4700 3675);
PAINT GREEN (-4700 3675);
DISPLAY INVISIBLE (-4700 3675);
FORCEPROP 1 LAST CDS_LMAN_SYM_OUTLINE -650,2525,650,-2525
J 0
(-4700 3675);
DISPLAY 0.468085 (-4700 3675);
PAINT GREEN (-4700 3675);
DISPLAY INVISIBLE (-4700 3675);
FORCEPROP 2 LAST CDS_LIB pure_quanta
J 0
(-4700 3675);
DISPLAY INVISIBLE (-4700 3675);
FORCEPROP 1 LAST PATH I167
J 0
(-4700 3675);
DISPLAY 0.723404 (-4700 3675);
PAINT GREEN (-4700 3675);
DISPLAY INVISIBLE (-4700 3675);
FORCEADD OFFPAGE..3
(-2700 6075);
FORCEPROP 2 LAST $XR0 103 
J 0
(-2486 6075);
DISPLAY 0.638298 (-2486 6075);
PAINT MONO (-2486 6075);
FORCEPROP 2 LAST PATH I168
J 0
(-2475 6125);
DISPLAY 1.021277 (-2475 6125);
DISPLAY INVISIBLE (-2475 6125);
FORCEPROP 1 LAST COMMENT_BODY TRUE
J 0
(-2750 5975);
DISPLAY 0.872340 (-2750 5975);
PAINT GREEN (-2750 5975);
DISPLAY INVISIBLE (-2750 5975);
FORCEPROP 1 LAST OFFPAGE TRUE
J 0
(-2375 5950);
DISPLAY 0.872340 (-2375 5950);
PAINT GREEN (-2375 5950);
DISPLAY INVISIBLE (-2375 5950);
FORCEPROP 2 LAST CDS_LIB mstr_standard
J 0
(-2700 6075);
DISPLAY 0.723404 (-2700 6075);
PAINT MONO (-2700 6075);
DISPLAY INVISIBLE (-2700 6075);
FORCEADD OFFPAGE..3
(-2700 4275);
FORCEPROP 2 LAST $XR0 103 
J 0
(-2486 4275);
DISPLAY 0.638298 (-2486 4275);
PAINT MONO (-2486 4275);
FORCEPROP 2 LAST PATH I169
J 0
(-2475 4325);
DISPLAY 1.021277 (-2475 4325);
DISPLAY INVISIBLE (-2475 4325);
FORCEPROP 1 LAST COMMENT_BODY TRUE
J 0
(-2750 4175);
DISPLAY 0.872340 (-2750 4175);
PAINT GREEN (-2750 4175);
DISPLAY INVISIBLE (-2750 4175);
FORCEPROP 1 LAST OFFPAGE TRUE
J 0
(-2375 4150);
DISPLAY 0.872340 (-2375 4150);
PAINT GREEN (-2375 4150);
DISPLAY INVISIBLE (-2375 4150);
FORCEPROP 2 LAST CDS_LIB mstr_standard
J 0
(-2700 4275);
DISPLAY 0.723404 (-2700 4275);
PAINT MONO (-2700 4275);
DISPLAY INVISIBLE (-2700 4275);
FORCEADD TAP..1
(-3425 6050);
FORCEPROP 3 LASTPIN (-3475 6050) SIG_NAME M_G_CPU1_SA_DQ<0>
J 0
(-3465 6060);
DISPLAY 0.659574 (-3465 6060);
PAINT MONO (-3465 6060);
DISPLAY INVISIBLE (-3465 6060);
FORCEPROP 1 LASTPIN (-3475 6050) BN 0
J 0
(-3487 6058);
DISPLAY 0.489362 (-3487 6058);
PAINT GREEN (-3487 6058);
FORCEPROP 2 LAST CDS_LIB mstr_standard
J 0
(-3425 6050);
DISPLAY 0.723404 (-3425 6050);
PAINT MONO (-3425 6050);
DISPLAY INVISIBLE (-3425 6050);
FORCEPROP 1 LAST BODY_TYPE PLUMBING
J 0
(-3425 6100);
DISPLAY 0.872340 (-3425 6100);
PAINT GREEN (-3425 6100);
DISPLAY INVISIBLE (-3425 6100);
FORCEPROP 1 LAST HDL_TAP TRUE
J 0
(-3100 5925);
DISPLAY 0.872340 (-3100 5925);
DISPLAY INVISIBLE (-3100 5925);
FORCEPROP 1 LAST PATH I170
J 0
(-3427 6050);
DISPLAY 0.872340 (-3427 6050);
PAINT GREEN (-3427 6050);
DISPLAY INVISIBLE (-3427 6050);
FORCEADD TAP..1
(-3425 6000);
FORCEPROP 3 LASTPIN (-3475 6000) SIG_NAME M_G_CPU1_SA_DQ<1>
J 0
(-3465 6010);
DISPLAY 0.659574 (-3465 6010);
PAINT MONO (-3465 6010);
DISPLAY INVISIBLE (-3465 6010);
FORCEPROP 1 LASTPIN (-3475 6000) BN 1
J 0
(-3487 6008);
DISPLAY 0.489362 (-3487 6008);
PAINT GREEN (-3487 6008);
FORCEPROP 2 LAST CDS_LIB mstr_standard
J 0
(-3425 6000);
DISPLAY 0.723404 (-3425 6000);
PAINT MONO (-3425 6000);
DISPLAY INVISIBLE (-3425 6000);
FORCEPROP 1 LAST BODY_TYPE PLUMBING
J 0
(-3425 6050);
DISPLAY 0.872340 (-3425 6050);
PAINT GREEN (-3425 6050);
DISPLAY INVISIBLE (-3425 6050);
FORCEPROP 1 LAST HDL_TAP TRUE
J 0
(-3100 5875);
DISPLAY 0.872340 (-3100 5875);
DISPLAY INVISIBLE (-3100 5875);
FORCEPROP 1 LAST PATH I171
J 0
(-3427 6000);
DISPLAY 0.872340 (-3427 6000);
PAINT GREEN (-3427 6000);
DISPLAY INVISIBLE (-3427 6000);
FORCEADD TAP..1
(-3425 5900);
FORCEPROP 3 LASTPIN (-3475 5900) SIG_NAME M_G_CPU1_SA_DQ<3>
J 0
(-3465 5910);
DISPLAY 0.659574 (-3465 5910);
PAINT MONO (-3465 5910);
DISPLAY INVISIBLE (-3465 5910);
FORCEPROP 1 LASTPIN (-3475 5900) BN 3
J 0
(-3487 5908);
DISPLAY 0.489362 (-3487 5908);
PAINT GREEN (-3487 5908);
FORCEPROP 2 LAST CDS_LIB mstr_standard
J 0
(-3425 5900);
DISPLAY 0.723404 (-3425 5900);
PAINT MONO (-3425 5900);
DISPLAY INVISIBLE (-3425 5900);
FORCEPROP 1 LAST BODY_TYPE PLUMBING
J 0
(-3425 5950);
DISPLAY 0.872340 (-3425 5950);
PAINT GREEN (-3425 5950);
DISPLAY INVISIBLE (-3425 5950);
FORCEPROP 1 LAST HDL_TAP TRUE
J 0
(-3100 5775);
DISPLAY 0.872340 (-3100 5775);
DISPLAY INVISIBLE (-3100 5775);
FORCEPROP 1 LAST PATH I172
J 0
(-3427 5900);
DISPLAY 0.872340 (-3427 5900);
PAINT GREEN (-3427 5900);
DISPLAY INVISIBLE (-3427 5900);
FORCEADD TAP..1
(-3425 5950);
FORCEPROP 3 LASTPIN (-3475 5950) SIG_NAME M_G_CPU1_SA_DQ<2>
J 0
(-3465 5960);
DISPLAY 0.659574 (-3465 5960);
PAINT MONO (-3465 5960);
DISPLAY INVISIBLE (-3465 5960);
FORCEPROP 1 LASTPIN (-3475 5950) BN 2
J 0
(-3487 5958);
DISPLAY 0.489362 (-3487 5958);
PAINT GREEN (-3487 5958);
FORCEPROP 2 LAST CDS_LIB mstr_standard
J 0
(-3425 5950);
DISPLAY 0.723404 (-3425 5950);
PAINT MONO (-3425 5950);
DISPLAY INVISIBLE (-3425 5950);
FORCEPROP 1 LAST BODY_TYPE PLUMBING
J 0
(-3425 6000);
DISPLAY 0.872340 (-3425 6000);
PAINT GREEN (-3425 6000);
DISPLAY INVISIBLE (-3425 6000);
FORCEPROP 1 LAST HDL_TAP TRUE
J 0
(-3100 5825);
DISPLAY 0.872340 (-3100 5825);
DISPLAY INVISIBLE (-3100 5825);
FORCEPROP 1 LAST PATH I173
J 0
(-3427 5950);
DISPLAY 0.872340 (-3427 5950);
PAINT GREEN (-3427 5950);
DISPLAY INVISIBLE (-3427 5950);
FORCEADD TAP..1
(-3425 5850);
FORCEPROP 3 LASTPIN (-3475 5850) SIG_NAME M_G_CPU1_SA_DQ<4>
J 0
(-3465 5860);
DISPLAY 0.659574 (-3465 5860);
PAINT MONO (-3465 5860);
DISPLAY INVISIBLE (-3465 5860);
FORCEPROP 1 LASTPIN (-3475 5850) BN 4
J 0
(-3487 5858);
DISPLAY 0.489362 (-3487 5858);
PAINT GREEN (-3487 5858);
FORCEPROP 2 LAST CDS_LIB mstr_standard
J 0
(-3425 5850);
DISPLAY 0.723404 (-3425 5850);
PAINT MONO (-3425 5850);
DISPLAY INVISIBLE (-3425 5850);
FORCEPROP 1 LAST BODY_TYPE PLUMBING
J 0
(-3425 5900);
DISPLAY 0.872340 (-3425 5900);
PAINT GREEN (-3425 5900);
DISPLAY INVISIBLE (-3425 5900);
FORCEPROP 1 LAST HDL_TAP TRUE
J 0
(-3100 5725);
DISPLAY 0.872340 (-3100 5725);
DISPLAY INVISIBLE (-3100 5725);
FORCEPROP 1 LAST PATH I174
J 0
(-3427 5850);
DISPLAY 0.872340 (-3427 5850);
PAINT GREEN (-3427 5850);
DISPLAY INVISIBLE (-3427 5850);
FORCEADD TAP..1
(-3425 5800);
FORCEPROP 3 LASTPIN (-3475 5800) SIG_NAME M_G_CPU1_SA_DQ<5>
J 0
(-3465 5810);
DISPLAY 0.659574 (-3465 5810);
PAINT MONO (-3465 5810);
DISPLAY INVISIBLE (-3465 5810);
FORCEPROP 1 LASTPIN (-3475 5800) BN 5
J 0
(-3487 5808);
DISPLAY 0.489362 (-3487 5808);
PAINT GREEN (-3487 5808);
FORCEPROP 2 LAST CDS_LIB mstr_standard
J 0
(-3425 5800);
DISPLAY 0.723404 (-3425 5800);
PAINT MONO (-3425 5800);
DISPLAY INVISIBLE (-3425 5800);
FORCEPROP 1 LAST BODY_TYPE PLUMBING
J 0
(-3425 5850);
DISPLAY 0.872340 (-3425 5850);
PAINT GREEN (-3425 5850);
DISPLAY INVISIBLE (-3425 5850);
FORCEPROP 1 LAST HDL_TAP TRUE
J 0
(-3100 5675);
DISPLAY 0.872340 (-3100 5675);
DISPLAY INVISIBLE (-3100 5675);
FORCEPROP 1 LAST PATH I175
J 0
(-3427 5800);
DISPLAY 0.872340 (-3427 5800);
PAINT GREEN (-3427 5800);
DISPLAY INVISIBLE (-3427 5800);
FORCEADD TAP..1
(-3425 5750);
FORCEPROP 3 LASTPIN (-3475 5750) SIG_NAME M_G_CPU1_SA_DQ<6>
J 0
(-3465 5760);
DISPLAY 0.659574 (-3465 5760);
PAINT MONO (-3465 5760);
DISPLAY INVISIBLE (-3465 5760);
FORCEPROP 1 LASTPIN (-3475 5750) BN 6
J 0
(-3487 5758);
DISPLAY 0.489362 (-3487 5758);
PAINT GREEN (-3487 5758);
FORCEPROP 2 LAST CDS_LIB mstr_standard
J 0
(-3425 5750);
DISPLAY 0.723404 (-3425 5750);
PAINT MONO (-3425 5750);
DISPLAY INVISIBLE (-3425 5750);
FORCEPROP 1 LAST BODY_TYPE PLUMBING
J 0
(-3425 5800);
DISPLAY 0.872340 (-3425 5800);
PAINT GREEN (-3425 5800);
DISPLAY INVISIBLE (-3425 5800);
FORCEPROP 1 LAST HDL_TAP TRUE
J 0
(-3100 5625);
DISPLAY 0.872340 (-3100 5625);
DISPLAY INVISIBLE (-3100 5625);
FORCEPROP 1 LAST PATH I176
J 0
(-3427 5750);
DISPLAY 0.872340 (-3427 5750);
PAINT GREEN (-3427 5750);
DISPLAY INVISIBLE (-3427 5750);
FORCEADD TAP..1
(-3425 5700);
FORCEPROP 3 LASTPIN (-3475 5700) SIG_NAME M_G_CPU1_SA_DQ<7>
J 0
(-3465 5710);
DISPLAY 0.659574 (-3465 5710);
PAINT MONO (-3465 5710);
DISPLAY INVISIBLE (-3465 5710);
FORCEPROP 1 LASTPIN (-3475 5700) BN 7
J 0
(-3487 5708);
DISPLAY 0.489362 (-3487 5708);
PAINT GREEN (-3487 5708);
FORCEPROP 2 LAST CDS_LIB mstr_standard
J 0
(-3425 5700);
DISPLAY 0.723404 (-3425 5700);
PAINT MONO (-3425 5700);
DISPLAY INVISIBLE (-3425 5700);
FORCEPROP 1 LAST BODY_TYPE PLUMBING
J 0
(-3425 5750);
DISPLAY 0.872340 (-3425 5750);
PAINT GREEN (-3425 5750);
DISPLAY INVISIBLE (-3425 5750);
FORCEPROP 1 LAST HDL_TAP TRUE
J 0
(-3100 5575);
DISPLAY 0.872340 (-3100 5575);
DISPLAY INVISIBLE (-3100 5575);
FORCEPROP 1 LAST PATH I177
J 0
(-3427 5700);
DISPLAY 0.872340 (-3427 5700);
PAINT GREEN (-3427 5700);
DISPLAY INVISIBLE (-3427 5700);
FORCEADD TAP..1
(-3425 5600);
FORCEPROP 3 LASTPIN (-3475 5600) SIG_NAME M_G_CPU1_SA_DQ<8>
J 0
(-3465 5610);
DISPLAY 0.659574 (-3465 5610);
PAINT MONO (-3465 5610);
DISPLAY INVISIBLE (-3465 5610);
FORCEPROP 1 LASTPIN (-3475 5600) BN 8
J 0
(-3487 5608);
DISPLAY 0.489362 (-3487 5608);
PAINT GREEN (-3487 5608);
FORCEPROP 2 LAST CDS_LIB mstr_standard
J 0
(-3425 5600);
DISPLAY 0.723404 (-3425 5600);
PAINT MONO (-3425 5600);
DISPLAY INVISIBLE (-3425 5600);
FORCEPROP 1 LAST BODY_TYPE PLUMBING
J 0
(-3425 5650);
DISPLAY 0.872340 (-3425 5650);
PAINT GREEN (-3425 5650);
DISPLAY INVISIBLE (-3425 5650);
FORCEPROP 1 LAST HDL_TAP TRUE
J 0
(-3100 5475);
DISPLAY 0.872340 (-3100 5475);
DISPLAY INVISIBLE (-3100 5475);
FORCEPROP 1 LAST PATH I178
J 0
(-3427 5600);
DISPLAY 0.872340 (-3427 5600);
PAINT GREEN (-3427 5600);
DISPLAY INVISIBLE (-3427 5600);
FORCEADD TAP..1
(-3425 5550);
FORCEPROP 3 LASTPIN (-3475 5550) SIG_NAME M_G_CPU1_SA_DQ<9>
J 0
(-3465 5560);
DISPLAY 0.659574 (-3465 5560);
PAINT MONO (-3465 5560);
DISPLAY INVISIBLE (-3465 5560);
FORCEPROP 1 LASTPIN (-3475 5550) BN 9
J 0
(-3487 5558);
DISPLAY 0.489362 (-3487 5558);
PAINT GREEN (-3487 5558);
FORCEPROP 2 LAST CDS_LIB mstr_standard
J 0
(-3425 5550);
DISPLAY 0.723404 (-3425 5550);
PAINT MONO (-3425 5550);
DISPLAY INVISIBLE (-3425 5550);
FORCEPROP 1 LAST BODY_TYPE PLUMBING
J 0
(-3425 5600);
DISPLAY 0.872340 (-3425 5600);
PAINT GREEN (-3425 5600);
DISPLAY INVISIBLE (-3425 5600);
FORCEPROP 1 LAST HDL_TAP TRUE
J 0
(-3100 5425);
DISPLAY 0.872340 (-3100 5425);
DISPLAY INVISIBLE (-3100 5425);
FORCEPROP 1 LAST PATH I179
J 0
(-3427 5550);
DISPLAY 0.872340 (-3427 5550);
PAINT GREEN (-3427 5550);
DISPLAY INVISIBLE (-3427 5550);
FORCEADD TAP..1
(-3425 5500);
FORCEPROP 3 LASTPIN (-3475 5500) SIG_NAME M_G_CPU1_SA_DQ<10>
J 0
(-3465 5510);
DISPLAY 0.659574 (-3465 5510);
PAINT MONO (-3465 5510);
DISPLAY INVISIBLE (-3465 5510);
FORCEPROP 1 LASTPIN (-3475 5500) BN 10
J 0
(-3487 5508);
DISPLAY 0.489362 (-3487 5508);
PAINT GREEN (-3487 5508);
FORCEPROP 2 LAST CDS_LIB mstr_standard
J 0
(-3425 5500);
DISPLAY 0.723404 (-3425 5500);
PAINT MONO (-3425 5500);
DISPLAY INVISIBLE (-3425 5500);
FORCEPROP 1 LAST BODY_TYPE PLUMBING
J 0
(-3425 5550);
DISPLAY 0.872340 (-3425 5550);
PAINT GREEN (-3425 5550);
DISPLAY INVISIBLE (-3425 5550);
FORCEPROP 1 LAST HDL_TAP TRUE
J 0
(-3100 5375);
DISPLAY 0.872340 (-3100 5375);
DISPLAY INVISIBLE (-3100 5375);
FORCEPROP 1 LAST PATH I180
J 0
(-3427 5500);
DISPLAY 0.872340 (-3427 5500);
PAINT GREEN (-3427 5500);
DISPLAY INVISIBLE (-3427 5500);
FORCEADD TAP..1
(-3425 5450);
FORCEPROP 3 LASTPIN (-3475 5450) SIG_NAME M_G_CPU1_SA_DQ<11>
J 0
(-3465 5460);
DISPLAY 0.659574 (-3465 5460);
PAINT MONO (-3465 5460);
DISPLAY INVISIBLE (-3465 5460);
FORCEPROP 1 LASTPIN (-3475 5450) BN 11
J 0
(-3487 5458);
DISPLAY 0.489362 (-3487 5458);
PAINT GREEN (-3487 5458);
FORCEPROP 2 LAST CDS_LIB mstr_standard
J 0
(-3425 5450);
DISPLAY 0.723404 (-3425 5450);
PAINT MONO (-3425 5450);
DISPLAY INVISIBLE (-3425 5450);
FORCEPROP 1 LAST BODY_TYPE PLUMBING
J 0
(-3425 5500);
DISPLAY 0.872340 (-3425 5500);
PAINT GREEN (-3425 5500);
DISPLAY INVISIBLE (-3425 5500);
FORCEPROP 1 LAST HDL_TAP TRUE
J 0
(-3100 5325);
DISPLAY 0.872340 (-3100 5325);
DISPLAY INVISIBLE (-3100 5325);
FORCEPROP 1 LAST PATH I181
J 0
(-3427 5450);
DISPLAY 0.872340 (-3427 5450);
PAINT GREEN (-3427 5450);
DISPLAY INVISIBLE (-3427 5450);
FORCEADD TAP..1
(-3425 5400);
FORCEPROP 3 LASTPIN (-3475 5400) SIG_NAME M_G_CPU1_SA_DQ<12>
J 0
(-3465 5410);
DISPLAY 0.659574 (-3465 5410);
PAINT MONO (-3465 5410);
DISPLAY INVISIBLE (-3465 5410);
FORCEPROP 1 LASTPIN (-3475 5400) BN 12
J 0
(-3487 5408);
DISPLAY 0.489362 (-3487 5408);
PAINT GREEN (-3487 5408);
FORCEPROP 2 LAST CDS_LIB mstr_standard
J 0
(-3425 5400);
DISPLAY 0.723404 (-3425 5400);
PAINT MONO (-3425 5400);
DISPLAY INVISIBLE (-3425 5400);
FORCEPROP 1 LAST BODY_TYPE PLUMBING
J 0
(-3425 5450);
DISPLAY 0.872340 (-3425 5450);
PAINT GREEN (-3425 5450);
DISPLAY INVISIBLE (-3425 5450);
FORCEPROP 1 LAST HDL_TAP TRUE
J 0
(-3100 5275);
DISPLAY 0.872340 (-3100 5275);
DISPLAY INVISIBLE (-3100 5275);
FORCEPROP 1 LAST PATH I182
J 0
(-3427 5400);
DISPLAY 0.872340 (-3427 5400);
PAINT GREEN (-3427 5400);
DISPLAY INVISIBLE (-3427 5400);
FORCEADD TAP..1
(-3425 5350);
FORCEPROP 3 LASTPIN (-3475 5350) SIG_NAME M_G_CPU1_SA_DQ<13>
J 0
(-3465 5360);
DISPLAY 0.659574 (-3465 5360);
PAINT MONO (-3465 5360);
DISPLAY INVISIBLE (-3465 5360);
FORCEPROP 1 LASTPIN (-3475 5350) BN 13
J 0
(-3487 5358);
DISPLAY 0.489362 (-3487 5358);
PAINT GREEN (-3487 5358);
FORCEPROP 2 LAST CDS_LIB mstr_standard
J 0
(-3425 5350);
DISPLAY 0.723404 (-3425 5350);
PAINT MONO (-3425 5350);
DISPLAY INVISIBLE (-3425 5350);
FORCEPROP 1 LAST BODY_TYPE PLUMBING
J 0
(-3425 5400);
DISPLAY 0.872340 (-3425 5400);
PAINT GREEN (-3425 5400);
DISPLAY INVISIBLE (-3425 5400);
FORCEPROP 1 LAST HDL_TAP TRUE
J 0
(-3100 5225);
DISPLAY 0.872340 (-3100 5225);
DISPLAY INVISIBLE (-3100 5225);
FORCEPROP 1 LAST PATH I183
J 0
(-3427 5350);
DISPLAY 0.872340 (-3427 5350);
PAINT GREEN (-3427 5350);
DISPLAY INVISIBLE (-3427 5350);
FORCEADD TAP..1
(-3425 5250);
FORCEPROP 3 LASTPIN (-3475 5250) SIG_NAME M_G_CPU1_SA_DQ<15>
J 0
(-3465 5260);
DISPLAY 0.659574 (-3465 5260);
PAINT MONO (-3465 5260);
DISPLAY INVISIBLE (-3465 5260);
FORCEPROP 1 LASTPIN (-3475 5250) BN 15
J 0
(-3487 5258);
DISPLAY 0.489362 (-3487 5258);
PAINT GREEN (-3487 5258);
FORCEPROP 2 LAST CDS_LIB mstr_standard
J 0
(-3425 5250);
DISPLAY 0.723404 (-3425 5250);
PAINT MONO (-3425 5250);
DISPLAY INVISIBLE (-3425 5250);
FORCEPROP 1 LAST BODY_TYPE PLUMBING
J 0
(-3425 5300);
DISPLAY 0.872340 (-3425 5300);
PAINT GREEN (-3425 5300);
DISPLAY INVISIBLE (-3425 5300);
FORCEPROP 1 LAST HDL_TAP TRUE
J 0
(-3100 5125);
DISPLAY 0.872340 (-3100 5125);
DISPLAY INVISIBLE (-3100 5125);
FORCEPROP 1 LAST PATH I184
J 0
(-3427 5250);
DISPLAY 0.872340 (-3427 5250);
PAINT GREEN (-3427 5250);
DISPLAY INVISIBLE (-3427 5250);
FORCEADD TAP..1
(-3425 5300);
FORCEPROP 3 LASTPIN (-3475 5300) SIG_NAME M_G_CPU1_SA_DQ<14>
J 0
(-3465 5310);
DISPLAY 0.659574 (-3465 5310);
PAINT MONO (-3465 5310);
DISPLAY INVISIBLE (-3465 5310);
FORCEPROP 1 LASTPIN (-3475 5300) BN 14
J 0
(-3487 5308);
DISPLAY 0.489362 (-3487 5308);
PAINT GREEN (-3487 5308);
FORCEPROP 2 LAST CDS_LIB mstr_standard
J 0
(-3425 5300);
DISPLAY 0.723404 (-3425 5300);
PAINT MONO (-3425 5300);
DISPLAY INVISIBLE (-3425 5300);
FORCEPROP 1 LAST BODY_TYPE PLUMBING
J 0
(-3425 5350);
DISPLAY 0.872340 (-3425 5350);
PAINT GREEN (-3425 5350);
DISPLAY INVISIBLE (-3425 5350);
FORCEPROP 1 LAST HDL_TAP TRUE
J 0
(-3100 5175);
DISPLAY 0.872340 (-3100 5175);
DISPLAY INVISIBLE (-3100 5175);
FORCEPROP 1 LAST PATH I185
J 0
(-3427 5300);
DISPLAY 0.872340 (-3427 5300);
PAINT GREEN (-3427 5300);
DISPLAY INVISIBLE (-3427 5300);
FORCEADD TAP..1
(-3425 5150);
FORCEPROP 3 LASTPIN (-3475 5150) SIG_NAME M_G_CPU1_SA_DQ<16>
J 0
(-3465 5160);
DISPLAY 0.659574 (-3465 5160);
PAINT MONO (-3465 5160);
DISPLAY INVISIBLE (-3465 5160);
FORCEPROP 1 LASTPIN (-3475 5150) BN 16
J 0
(-3487 5158);
DISPLAY 0.489362 (-3487 5158);
PAINT GREEN (-3487 5158);
FORCEPROP 2 LAST CDS_LIB mstr_standard
J 0
(-3425 5150);
DISPLAY 0.723404 (-3425 5150);
PAINT MONO (-3425 5150);
DISPLAY INVISIBLE (-3425 5150);
FORCEPROP 1 LAST BODY_TYPE PLUMBING
J 0
(-3425 5200);
DISPLAY 0.872340 (-3425 5200);
PAINT GREEN (-3425 5200);
DISPLAY INVISIBLE (-3425 5200);
FORCEPROP 1 LAST HDL_TAP TRUE
J 0
(-3100 5025);
DISPLAY 0.872340 (-3100 5025);
DISPLAY INVISIBLE (-3100 5025);
FORCEPROP 1 LAST PATH I186
J 0
(-3427 5150);
DISPLAY 0.872340 (-3427 5150);
PAINT GREEN (-3427 5150);
DISPLAY INVISIBLE (-3427 5150);
FORCEADD TAP..1
(-3425 5100);
FORCEPROP 3 LASTPIN (-3475 5100) SIG_NAME M_G_CPU1_SA_DQ<17>
J 0
(-3465 5110);
DISPLAY 0.659574 (-3465 5110);
PAINT MONO (-3465 5110);
DISPLAY INVISIBLE (-3465 5110);
FORCEPROP 1 LASTPIN (-3475 5100) BN 17
J 0
(-3487 5108);
DISPLAY 0.489362 (-3487 5108);
PAINT GREEN (-3487 5108);
FORCEPROP 2 LAST CDS_LIB mstr_standard
J 0
(-3425 5100);
DISPLAY 0.723404 (-3425 5100);
PAINT MONO (-3425 5100);
DISPLAY INVISIBLE (-3425 5100);
FORCEPROP 1 LAST BODY_TYPE PLUMBING
J 0
(-3425 5150);
DISPLAY 0.872340 (-3425 5150);
PAINT GREEN (-3425 5150);
DISPLAY INVISIBLE (-3425 5150);
FORCEPROP 1 LAST HDL_TAP TRUE
J 0
(-3100 4975);
DISPLAY 0.872340 (-3100 4975);
DISPLAY INVISIBLE (-3100 4975);
FORCEPROP 1 LAST PATH I187
J 0
(-3427 5100);
DISPLAY 0.872340 (-3427 5100);
PAINT GREEN (-3427 5100);
DISPLAY INVISIBLE (-3427 5100);
FORCEADD TAP..1
(-3425 5000);
FORCEPROP 3 LASTPIN (-3475 5000) SIG_NAME M_G_CPU1_SA_DQ<19>
J 0
(-3465 5010);
DISPLAY 0.659574 (-3465 5010);
PAINT MONO (-3465 5010);
DISPLAY INVISIBLE (-3465 5010);
FORCEPROP 1 LASTPIN (-3475 5000) BN 19
J 0
(-3487 5008);
DISPLAY 0.489362 (-3487 5008);
PAINT GREEN (-3487 5008);
FORCEPROP 2 LAST CDS_LIB mstr_standard
J 0
(-3425 5000);
DISPLAY 0.723404 (-3425 5000);
PAINT MONO (-3425 5000);
DISPLAY INVISIBLE (-3425 5000);
FORCEPROP 1 LAST BODY_TYPE PLUMBING
J 0
(-3425 5050);
DISPLAY 0.872340 (-3425 5050);
PAINT GREEN (-3425 5050);
DISPLAY INVISIBLE (-3425 5050);
FORCEPROP 1 LAST HDL_TAP TRUE
J 0
(-3100 4875);
DISPLAY 0.872340 (-3100 4875);
DISPLAY INVISIBLE (-3100 4875);
FORCEPROP 1 LAST PATH I188
J 0
(-3427 5000);
DISPLAY 0.872340 (-3427 5000);
PAINT GREEN (-3427 5000);
DISPLAY INVISIBLE (-3427 5000);
FORCEADD TAP..1
(-3425 5050);
FORCEPROP 3 LASTPIN (-3475 5050) SIG_NAME M_G_CPU1_SA_DQ<18>
J 0
(-3465 5060);
DISPLAY 0.659574 (-3465 5060);
PAINT MONO (-3465 5060);
DISPLAY INVISIBLE (-3465 5060);
FORCEPROP 1 LASTPIN (-3475 5050) BN 18
J 0
(-3487 5058);
DISPLAY 0.489362 (-3487 5058);
PAINT GREEN (-3487 5058);
FORCEPROP 2 LAST CDS_LIB mstr_standard
J 0
(-3425 5050);
DISPLAY 0.723404 (-3425 5050);
PAINT MONO (-3425 5050);
DISPLAY INVISIBLE (-3425 5050);
FORCEPROP 1 LAST BODY_TYPE PLUMBING
J 0
(-3425 5100);
DISPLAY 0.872340 (-3425 5100);
PAINT GREEN (-3425 5100);
DISPLAY INVISIBLE (-3425 5100);
FORCEPROP 1 LAST HDL_TAP TRUE
J 0
(-3100 4925);
DISPLAY 0.872340 (-3100 4925);
DISPLAY INVISIBLE (-3100 4925);
FORCEPROP 1 LAST PATH I189
J 0
(-3427 5050);
DISPLAY 0.872340 (-3427 5050);
PAINT GREEN (-3427 5050);
DISPLAY INVISIBLE (-3427 5050);
FORCEADD TAP..1
(-3425 4950);
FORCEPROP 3 LASTPIN (-3475 4950) SIG_NAME M_G_CPU1_SA_DQ<20>
J 0
(-3465 4960);
DISPLAY 0.659574 (-3465 4960);
PAINT MONO (-3465 4960);
DISPLAY INVISIBLE (-3465 4960);
FORCEPROP 1 LASTPIN (-3475 4950) BN 20
J 0
(-3487 4958);
DISPLAY 0.489362 (-3487 4958);
PAINT GREEN (-3487 4958);
FORCEPROP 2 LAST CDS_LIB mstr_standard
J 0
(-3425 4950);
DISPLAY 0.723404 (-3425 4950);
PAINT MONO (-3425 4950);
DISPLAY INVISIBLE (-3425 4950);
FORCEPROP 1 LAST BODY_TYPE PLUMBING
J 0
(-3425 5000);
DISPLAY 0.872340 (-3425 5000);
PAINT GREEN (-3425 5000);
DISPLAY INVISIBLE (-3425 5000);
FORCEPROP 1 LAST HDL_TAP TRUE
J 0
(-3100 4825);
DISPLAY 0.872340 (-3100 4825);
DISPLAY INVISIBLE (-3100 4825);
FORCEPROP 1 LAST PATH I190
J 0
(-3427 4950);
DISPLAY 0.872340 (-3427 4950);
PAINT GREEN (-3427 4950);
DISPLAY INVISIBLE (-3427 4950);
FORCEADD TAP..1
(-3425 4900);
FORCEPROP 3 LASTPIN (-3475 4900) SIG_NAME M_G_CPU1_SA_DQ<21>
J 0
(-3465 4910);
DISPLAY 0.659574 (-3465 4910);
PAINT MONO (-3465 4910);
DISPLAY INVISIBLE (-3465 4910);
FORCEPROP 1 LASTPIN (-3475 4900) BN 21
J 0
(-3487 4908);
DISPLAY 0.489362 (-3487 4908);
PAINT GREEN (-3487 4908);
FORCEPROP 2 LAST CDS_LIB mstr_standard
J 0
(-3425 4900);
DISPLAY 0.723404 (-3425 4900);
PAINT MONO (-3425 4900);
DISPLAY INVISIBLE (-3425 4900);
FORCEPROP 1 LAST BODY_TYPE PLUMBING
J 0
(-3425 4950);
DISPLAY 0.872340 (-3425 4950);
PAINT GREEN (-3425 4950);
DISPLAY INVISIBLE (-3425 4950);
FORCEPROP 1 LAST HDL_TAP TRUE
J 0
(-3100 4775);
DISPLAY 0.872340 (-3100 4775);
DISPLAY INVISIBLE (-3100 4775);
FORCEPROP 1 LAST PATH I191
J 0
(-3427 4900);
DISPLAY 0.872340 (-3427 4900);
PAINT GREEN (-3427 4900);
DISPLAY INVISIBLE (-3427 4900);
FORCEADD TAP..1
(-3425 4850);
FORCEPROP 3 LASTPIN (-3475 4850) SIG_NAME M_G_CPU1_SA_DQ<22>
J 0
(-3465 4860);
DISPLAY 0.659574 (-3465 4860);
PAINT MONO (-3465 4860);
DISPLAY INVISIBLE (-3465 4860);
FORCEPROP 1 LASTPIN (-3475 4850) BN 22
J 0
(-3487 4858);
DISPLAY 0.489362 (-3487 4858);
PAINT GREEN (-3487 4858);
FORCEPROP 2 LAST CDS_LIB mstr_standard
J 0
(-3425 4850);
DISPLAY 0.723404 (-3425 4850);
PAINT MONO (-3425 4850);
DISPLAY INVISIBLE (-3425 4850);
FORCEPROP 1 LAST BODY_TYPE PLUMBING
J 0
(-3425 4900);
DISPLAY 0.872340 (-3425 4900);
PAINT GREEN (-3425 4900);
DISPLAY INVISIBLE (-3425 4900);
FORCEPROP 1 LAST HDL_TAP TRUE
J 0
(-3100 4725);
DISPLAY 0.872340 (-3100 4725);
DISPLAY INVISIBLE (-3100 4725);
FORCEPROP 1 LAST PATH I192
J 0
(-3427 4850);
DISPLAY 0.872340 (-3427 4850);
PAINT GREEN (-3427 4850);
DISPLAY INVISIBLE (-3427 4850);
FORCEADD TAP..1
(-3425 4800);
FORCEPROP 3 LASTPIN (-3475 4800) SIG_NAME M_G_CPU1_SA_DQ<23>
J 0
(-3465 4810);
DISPLAY 0.659574 (-3465 4810);
PAINT MONO (-3465 4810);
DISPLAY INVISIBLE (-3465 4810);
FORCEPROP 1 LASTPIN (-3475 4800) BN 23
J 0
(-3487 4808);
DISPLAY 0.489362 (-3487 4808);
PAINT GREEN (-3487 4808);
FORCEPROP 2 LAST CDS_LIB mstr_standard
J 0
(-3425 4800);
DISPLAY 0.723404 (-3425 4800);
PAINT MONO (-3425 4800);
DISPLAY INVISIBLE (-3425 4800);
FORCEPROP 1 LAST BODY_TYPE PLUMBING
J 0
(-3425 4850);
DISPLAY 0.872340 (-3425 4850);
PAINT GREEN (-3425 4850);
DISPLAY INVISIBLE (-3425 4850);
FORCEPROP 1 LAST HDL_TAP TRUE
J 0
(-3100 4675);
DISPLAY 0.872340 (-3100 4675);
DISPLAY INVISIBLE (-3100 4675);
FORCEPROP 1 LAST PATH I193
J 0
(-3427 4800);
DISPLAY 0.872340 (-3427 4800);
PAINT GREEN (-3427 4800);
DISPLAY INVISIBLE (-3427 4800);
FORCEADD TAP..1
(-3425 4700);
FORCEPROP 3 LASTPIN (-3475 4700) SIG_NAME M_G_CPU1_SA_DQ<24>
J 0
(-3465 4710);
DISPLAY 0.659574 (-3465 4710);
PAINT MONO (-3465 4710);
DISPLAY INVISIBLE (-3465 4710);
FORCEPROP 1 LASTPIN (-3475 4700) BN 24
J 0
(-3487 4708);
DISPLAY 0.489362 (-3487 4708);
PAINT GREEN (-3487 4708);
FORCEPROP 2 LAST CDS_LIB mstr_standard
J 0
(-3425 4700);
DISPLAY 0.723404 (-3425 4700);
PAINT MONO (-3425 4700);
DISPLAY INVISIBLE (-3425 4700);
FORCEPROP 1 LAST BODY_TYPE PLUMBING
J 0
(-3425 4750);
DISPLAY 0.872340 (-3425 4750);
PAINT GREEN (-3425 4750);
DISPLAY INVISIBLE (-3425 4750);
FORCEPROP 1 LAST HDL_TAP TRUE
J 0
(-3100 4575);
DISPLAY 0.872340 (-3100 4575);
DISPLAY INVISIBLE (-3100 4575);
FORCEPROP 1 LAST PATH I194
J 0
(-3427 4700);
DISPLAY 0.872340 (-3427 4700);
PAINT GREEN (-3427 4700);
DISPLAY INVISIBLE (-3427 4700);
FORCEADD TAP..1
(-3425 4650);
FORCEPROP 3 LASTPIN (-3475 4650) SIG_NAME M_G_CPU1_SA_DQ<25>
J 0
(-3465 4660);
DISPLAY 0.659574 (-3465 4660);
PAINT MONO (-3465 4660);
DISPLAY INVISIBLE (-3465 4660);
FORCEPROP 1 LASTPIN (-3475 4650) BN 25
J 0
(-3487 4658);
DISPLAY 0.489362 (-3487 4658);
PAINT GREEN (-3487 4658);
FORCEPROP 2 LAST CDS_LIB mstr_standard
J 0
(-3425 4650);
DISPLAY 0.723404 (-3425 4650);
PAINT MONO (-3425 4650);
DISPLAY INVISIBLE (-3425 4650);
FORCEPROP 1 LAST BODY_TYPE PLUMBING
J 0
(-3425 4700);
DISPLAY 0.872340 (-3425 4700);
PAINT GREEN (-3425 4700);
DISPLAY INVISIBLE (-3425 4700);
FORCEPROP 1 LAST HDL_TAP TRUE
J 0
(-3100 4525);
DISPLAY 0.872340 (-3100 4525);
DISPLAY INVISIBLE (-3100 4525);
FORCEPROP 1 LAST PATH I195
J 0
(-3427 4650);
DISPLAY 0.872340 (-3427 4650);
PAINT GREEN (-3427 4650);
DISPLAY INVISIBLE (-3427 4650);
FORCEADD TAP..1
(-3425 4600);
FORCEPROP 3 LASTPIN (-3475 4600) SIG_NAME M_G_CPU1_SA_DQ<26>
J 0
(-3465 4610);
DISPLAY 0.659574 (-3465 4610);
PAINT MONO (-3465 4610);
DISPLAY INVISIBLE (-3465 4610);
FORCEPROP 1 LASTPIN (-3475 4600) BN 26
J 0
(-3487 4608);
DISPLAY 0.489362 (-3487 4608);
PAINT GREEN (-3487 4608);
FORCEPROP 2 LAST CDS_LIB mstr_standard
J 0
(-3425 4600);
DISPLAY 0.723404 (-3425 4600);
PAINT MONO (-3425 4600);
DISPLAY INVISIBLE (-3425 4600);
FORCEPROP 1 LAST BODY_TYPE PLUMBING
J 0
(-3425 4650);
DISPLAY 0.872340 (-3425 4650);
PAINT GREEN (-3425 4650);
DISPLAY INVISIBLE (-3425 4650);
FORCEPROP 1 LAST HDL_TAP TRUE
J 0
(-3100 4475);
DISPLAY 0.872340 (-3100 4475);
DISPLAY INVISIBLE (-3100 4475);
FORCEPROP 1 LAST PATH I196
J 0
(-3427 4600);
DISPLAY 0.872340 (-3427 4600);
PAINT GREEN (-3427 4600);
DISPLAY INVISIBLE (-3427 4600);
FORCEADD TAP..1
(-3425 4550);
FORCEPROP 3 LASTPIN (-3475 4550) SIG_NAME M_G_CPU1_SA_DQ<27>
J 0
(-3465 4560);
DISPLAY 0.659574 (-3465 4560);
PAINT MONO (-3465 4560);
DISPLAY INVISIBLE (-3465 4560);
FORCEPROP 1 LASTPIN (-3475 4550) BN 27
J 0
(-3487 4558);
DISPLAY 0.489362 (-3487 4558);
PAINT GREEN (-3487 4558);
FORCEPROP 2 LAST CDS_LIB mstr_standard
J 0
(-3425 4550);
DISPLAY 0.723404 (-3425 4550);
PAINT MONO (-3425 4550);
DISPLAY INVISIBLE (-3425 4550);
FORCEPROP 1 LAST BODY_TYPE PLUMBING
J 0
(-3425 4600);
DISPLAY 0.872340 (-3425 4600);
PAINT GREEN (-3425 4600);
DISPLAY INVISIBLE (-3425 4600);
FORCEPROP 1 LAST HDL_TAP TRUE
J 0
(-3100 4425);
DISPLAY 0.872340 (-3100 4425);
DISPLAY INVISIBLE (-3100 4425);
FORCEPROP 1 LAST PATH I197
J 0
(-3427 4550);
DISPLAY 0.872340 (-3427 4550);
PAINT GREEN (-3427 4550);
DISPLAY INVISIBLE (-3427 4550);
FORCEADD TAP..1
(-3425 4500);
FORCEPROP 3 LASTPIN (-3475 4500) SIG_NAME M_G_CPU1_SA_DQ<28>
J 0
(-3465 4510);
DISPLAY 0.659574 (-3465 4510);
PAINT MONO (-3465 4510);
DISPLAY INVISIBLE (-3465 4510);
FORCEPROP 1 LASTPIN (-3475 4500) BN 28
J 0
(-3487 4508);
DISPLAY 0.489362 (-3487 4508);
PAINT GREEN (-3487 4508);
FORCEPROP 2 LAST CDS_LIB mstr_standard
J 0
(-3425 4500);
DISPLAY 0.723404 (-3425 4500);
PAINT MONO (-3425 4500);
DISPLAY INVISIBLE (-3425 4500);
FORCEPROP 1 LAST BODY_TYPE PLUMBING
J 0
(-3425 4550);
DISPLAY 0.872340 (-3425 4550);
PAINT GREEN (-3425 4550);
DISPLAY INVISIBLE (-3425 4550);
FORCEPROP 1 LAST HDL_TAP TRUE
J 0
(-3100 4375);
DISPLAY 0.872340 (-3100 4375);
DISPLAY INVISIBLE (-3100 4375);
FORCEPROP 1 LAST PATH I198
J 0
(-3427 4500);
DISPLAY 0.872340 (-3427 4500);
PAINT GREEN (-3427 4500);
DISPLAY INVISIBLE (-3427 4500);
FORCEADD TAP..1
(-3425 4450);
FORCEPROP 3 LASTPIN (-3475 4450) SIG_NAME M_G_CPU1_SA_DQ<29>
J 0
(-3465 4460);
DISPLAY 0.659574 (-3465 4460);
PAINT MONO (-3465 4460);
DISPLAY INVISIBLE (-3465 4460);
FORCEPROP 1 LASTPIN (-3475 4450) BN 29
J 0
(-3487 4458);
DISPLAY 0.489362 (-3487 4458);
PAINT GREEN (-3487 4458);
FORCEPROP 2 LAST CDS_LIB mstr_standard
J 0
(-3425 4450);
DISPLAY 0.723404 (-3425 4450);
PAINT MONO (-3425 4450);
DISPLAY INVISIBLE (-3425 4450);
FORCEPROP 1 LAST BODY_TYPE PLUMBING
J 0
(-3425 4500);
DISPLAY 0.872340 (-3425 4500);
PAINT GREEN (-3425 4500);
DISPLAY INVISIBLE (-3425 4500);
FORCEPROP 1 LAST HDL_TAP TRUE
J 0
(-3100 4325);
DISPLAY 0.872340 (-3100 4325);
DISPLAY INVISIBLE (-3100 4325);
FORCEPROP 1 LAST PATH I199
J 0
(-3427 4450);
DISPLAY 0.872340 (-3427 4450);
PAINT GREEN (-3427 4450);
DISPLAY INVISIBLE (-3427 4450);
FORCEADD TAP..1
(-3425 4400);
FORCEPROP 3 LASTPIN (-3475 4400) SIG_NAME M_G_CPU1_SA_DQ<30>
J 0
(-3465 4410);
DISPLAY 0.659574 (-3465 4410);
PAINT MONO (-3465 4410);
DISPLAY INVISIBLE (-3465 4410);
FORCEPROP 1 LASTPIN (-3475 4400) BN 30
J 0
(-3487 4408);
DISPLAY 0.489362 (-3487 4408);
PAINT GREEN (-3487 4408);
FORCEPROP 2 LAST CDS_LIB mstr_standard
J 0
(-3425 4400);
DISPLAY 0.723404 (-3425 4400);
PAINT MONO (-3425 4400);
DISPLAY INVISIBLE (-3425 4400);
FORCEPROP 1 LAST BODY_TYPE PLUMBING
J 0
(-3425 4450);
DISPLAY 0.872340 (-3425 4450);
PAINT GREEN (-3425 4450);
DISPLAY INVISIBLE (-3425 4450);
FORCEPROP 1 LAST HDL_TAP TRUE
J 0
(-3100 4275);
DISPLAY 0.872340 (-3100 4275);
DISPLAY INVISIBLE (-3100 4275);
FORCEPROP 1 LAST PATH I200
J 0
(-3427 4400);
DISPLAY 0.872340 (-3427 4400);
PAINT GREEN (-3427 4400);
DISPLAY INVISIBLE (-3427 4400);
FORCEADD TAP..1
(-3425 4350);
FORCEPROP 3 LASTPIN (-3475 4350) SIG_NAME M_G_CPU1_SA_DQ<31>
J 0
(-3465 4360);
DISPLAY 0.659574 (-3465 4360);
PAINT MONO (-3465 4360);
DISPLAY INVISIBLE (-3465 4360);
FORCEPROP 1 LASTPIN (-3475 4350) BN 31
J 0
(-3487 4358);
DISPLAY 0.489362 (-3487 4358);
PAINT GREEN (-3487 4358);
FORCEPROP 2 LAST CDS_LIB mstr_standard
J 0
(-3425 4350);
DISPLAY 0.723404 (-3425 4350);
PAINT MONO (-3425 4350);
DISPLAY INVISIBLE (-3425 4350);
FORCEPROP 1 LAST BODY_TYPE PLUMBING
J 0
(-3425 4400);
DISPLAY 0.872340 (-3425 4400);
PAINT GREEN (-3425 4400);
DISPLAY INVISIBLE (-3425 4400);
FORCEPROP 1 LAST HDL_TAP TRUE
J 0
(-3100 4225);
DISPLAY 0.872340 (-3100 4225);
DISPLAY INVISIBLE (-3100 4225);
FORCEPROP 1 LAST PATH I201
J 0
(-3427 4350);
DISPLAY 0.872340 (-3427 4350);
PAINT GREEN (-3427 4350);
DISPLAY INVISIBLE (-3427 4350);
FORCEADD TAP..1
(-3425 4250);
FORCEPROP 3 LASTPIN (-3475 4250) SIG_NAME M_G_CPU1_SB_DQ<0>
J 0
(-3465 4260);
DISPLAY 0.659574 (-3465 4260);
PAINT MONO (-3465 4260);
DISPLAY INVISIBLE (-3465 4260);
FORCEPROP 1 LASTPIN (-3475 4250) BN 0
J 0
(-3487 4258);
DISPLAY 0.489362 (-3487 4258);
PAINT GREEN (-3487 4258);
FORCEPROP 2 LAST CDS_LIB mstr_standard
J 0
(-3425 4250);
DISPLAY 0.723404 (-3425 4250);
PAINT MONO (-3425 4250);
DISPLAY INVISIBLE (-3425 4250);
FORCEPROP 1 LAST BODY_TYPE PLUMBING
J 0
(-3425 4300);
DISPLAY 0.872340 (-3425 4300);
PAINT GREEN (-3425 4300);
DISPLAY INVISIBLE (-3425 4300);
FORCEPROP 1 LAST HDL_TAP TRUE
J 0
(-3100 4125);
DISPLAY 0.872340 (-3100 4125);
DISPLAY INVISIBLE (-3100 4125);
FORCEPROP 1 LAST PATH I202
J 0
(-3427 4250);
DISPLAY 0.872340 (-3427 4250);
PAINT GREEN (-3427 4250);
DISPLAY INVISIBLE (-3427 4250);
FORCEADD TAP..1
(-3425 4200);
FORCEPROP 3 LASTPIN (-3475 4200) SIG_NAME M_G_CPU1_SB_DQ<1>
J 0
(-3465 4210);
DISPLAY 0.659574 (-3465 4210);
PAINT MONO (-3465 4210);
DISPLAY INVISIBLE (-3465 4210);
FORCEPROP 1 LASTPIN (-3475 4200) BN 1
J 0
(-3487 4208);
DISPLAY 0.489362 (-3487 4208);
PAINT GREEN (-3487 4208);
FORCEPROP 2 LAST CDS_LIB mstr_standard
J 0
(-3425 4200);
DISPLAY 0.723404 (-3425 4200);
PAINT MONO (-3425 4200);
DISPLAY INVISIBLE (-3425 4200);
FORCEPROP 1 LAST BODY_TYPE PLUMBING
J 0
(-3425 4250);
DISPLAY 0.872340 (-3425 4250);
PAINT GREEN (-3425 4250);
DISPLAY INVISIBLE (-3425 4250);
FORCEPROP 1 LAST HDL_TAP TRUE
J 0
(-3100 4075);
DISPLAY 0.872340 (-3100 4075);
DISPLAY INVISIBLE (-3100 4075);
FORCEPROP 1 LAST PATH I203
J 0
(-3427 4200);
DISPLAY 0.872340 (-3427 4200);
PAINT GREEN (-3427 4200);
DISPLAY INVISIBLE (-3427 4200);
FORCEADD TAP..1
(-3425 4100);
FORCEPROP 3 LASTPIN (-3475 4100) SIG_NAME M_G_CPU1_SB_DQ<3>
J 0
(-3465 4110);
DISPLAY 0.659574 (-3465 4110);
PAINT MONO (-3465 4110);
DISPLAY INVISIBLE (-3465 4110);
FORCEPROP 1 LASTPIN (-3475 4100) BN 3
J 0
(-3487 4108);
DISPLAY 0.489362 (-3487 4108);
PAINT GREEN (-3487 4108);
FORCEPROP 2 LAST CDS_LIB mstr_standard
J 0
(-3425 4100);
DISPLAY 0.723404 (-3425 4100);
PAINT MONO (-3425 4100);
DISPLAY INVISIBLE (-3425 4100);
FORCEPROP 1 LAST BODY_TYPE PLUMBING
J 0
(-3425 4150);
DISPLAY 0.872340 (-3425 4150);
PAINT GREEN (-3425 4150);
DISPLAY INVISIBLE (-3425 4150);
FORCEPROP 1 LAST HDL_TAP TRUE
J 0
(-3100 3975);
DISPLAY 0.872340 (-3100 3975);
DISPLAY INVISIBLE (-3100 3975);
FORCEPROP 1 LAST PATH I204
J 0
(-3427 4100);
DISPLAY 0.872340 (-3427 4100);
PAINT GREEN (-3427 4100);
DISPLAY INVISIBLE (-3427 4100);
FORCEADD TAP..1
(-3425 4150);
FORCEPROP 3 LASTPIN (-3475 4150) SIG_NAME M_G_CPU1_SB_DQ<2>
J 0
(-3465 4160);
DISPLAY 0.659574 (-3465 4160);
PAINT MONO (-3465 4160);
DISPLAY INVISIBLE (-3465 4160);
FORCEPROP 1 LASTPIN (-3475 4150) BN 2
J 0
(-3487 4158);
DISPLAY 0.489362 (-3487 4158);
PAINT GREEN (-3487 4158);
FORCEPROP 2 LAST CDS_LIB mstr_standard
J 0
(-3425 4150);
DISPLAY 0.723404 (-3425 4150);
PAINT MONO (-3425 4150);
DISPLAY INVISIBLE (-3425 4150);
FORCEPROP 1 LAST BODY_TYPE PLUMBING
J 0
(-3425 4200);
DISPLAY 0.872340 (-3425 4200);
PAINT GREEN (-3425 4200);
DISPLAY INVISIBLE (-3425 4200);
FORCEPROP 1 LAST HDL_TAP TRUE
J 0
(-3100 4025);
DISPLAY 0.872340 (-3100 4025);
DISPLAY INVISIBLE (-3100 4025);
FORCEPROP 1 LAST PATH I205
J 0
(-3427 4150);
DISPLAY 0.872340 (-3427 4150);
PAINT GREEN (-3427 4150);
DISPLAY INVISIBLE (-3427 4150);
FORCEADD OFFPAGE..6
R 2
(-2825 2500);
FORCEPROP 2 LAST $XR0 103 
J 0
(-2611 2500);
DISPLAY 0.638298 (-2611 2500);
PAINT MONO (-2611 2500);
FORCEPROP 2 LAST PATH I206
J 0
(-2600 2550);
DISPLAY 1.021277 (-2600 2550);
DISPLAY INVISIBLE (-2600 2550);
FORCEPROP 1 LAST COMMENT_BODY TRUE
J 2
(-2925 2425);
DISPLAY 0.872340 (-2925 2425);
PAINT GREEN (-2925 2425);
DISPLAY INVISIBLE (-2925 2425);
FORCEPROP 1 LAST OFFPAGE TRUE
J 2
(-3150 2375);
DISPLAY 0.872340 (-3150 2375);
PAINT GREEN (-3150 2375);
DISPLAY INVISIBLE (-3150 2375);
FORCEPROP 2 LAST CDS_LIB mstr_standard
J 2
(-2825 2500);
DISPLAY 0.723404 (-2825 2500);
PAINT MONO (-2825 2500);
DISPLAY INVISIBLE (-2825 2500);
FORCEADD TAP..1
(-3425 4050);
FORCEPROP 3 LASTPIN (-3475 4050) SIG_NAME M_G_CPU1_SB_DQ<4>
J 0
(-3465 4060);
DISPLAY 0.659574 (-3465 4060);
PAINT MONO (-3465 4060);
DISPLAY INVISIBLE (-3465 4060);
FORCEPROP 1 LASTPIN (-3475 4050) BN 4
J 0
(-3487 4058);
DISPLAY 0.489362 (-3487 4058);
PAINT GREEN (-3487 4058);
FORCEPROP 2 LAST CDS_LIB mstr_standard
J 0
(-3425 4050);
DISPLAY 0.723404 (-3425 4050);
PAINT MONO (-3425 4050);
DISPLAY INVISIBLE (-3425 4050);
FORCEPROP 1 LAST BODY_TYPE PLUMBING
J 0
(-3425 4100);
DISPLAY 0.872340 (-3425 4100);
PAINT GREEN (-3425 4100);
DISPLAY INVISIBLE (-3425 4100);
FORCEPROP 1 LAST HDL_TAP TRUE
J 0
(-3100 3925);
DISPLAY 0.872340 (-3100 3925);
DISPLAY INVISIBLE (-3100 3925);
FORCEPROP 1 LAST PATH I207
J 0
(-3427 4050);
DISPLAY 0.872340 (-3427 4050);
PAINT GREEN (-3427 4050);
DISPLAY INVISIBLE (-3427 4050);
FORCEADD TAP..1
(-3425 4000);
FORCEPROP 3 LASTPIN (-3475 4000) SIG_NAME M_G_CPU1_SB_DQ<5>
J 0
(-3465 4010);
DISPLAY 0.659574 (-3465 4010);
PAINT MONO (-3465 4010);
DISPLAY INVISIBLE (-3465 4010);
FORCEPROP 1 LASTPIN (-3475 4000) BN 5
J 0
(-3487 4008);
DISPLAY 0.489362 (-3487 4008);
PAINT GREEN (-3487 4008);
FORCEPROP 2 LAST CDS_LIB mstr_standard
J 0
(-3425 4000);
DISPLAY 0.723404 (-3425 4000);
PAINT MONO (-3425 4000);
DISPLAY INVISIBLE (-3425 4000);
FORCEPROP 1 LAST BODY_TYPE PLUMBING
J 0
(-3425 4050);
DISPLAY 0.872340 (-3425 4050);
PAINT GREEN (-3425 4050);
DISPLAY INVISIBLE (-3425 4050);
FORCEPROP 1 LAST HDL_TAP TRUE
J 0
(-3100 3875);
DISPLAY 0.872340 (-3100 3875);
DISPLAY INVISIBLE (-3100 3875);
FORCEPROP 1 LAST PATH I208
J 0
(-3427 4000);
DISPLAY 0.872340 (-3427 4000);
PAINT GREEN (-3427 4000);
DISPLAY INVISIBLE (-3427 4000);
FORCEADD TAP..1
(-3425 3950);
FORCEPROP 3 LASTPIN (-3475 3950) SIG_NAME M_G_CPU1_SB_DQ<6>
J 0
(-3465 3960);
DISPLAY 0.659574 (-3465 3960);
PAINT MONO (-3465 3960);
DISPLAY INVISIBLE (-3465 3960);
FORCEPROP 1 LASTPIN (-3475 3950) BN 6
J 0
(-3487 3958);
DISPLAY 0.489362 (-3487 3958);
PAINT GREEN (-3487 3958);
FORCEPROP 2 LAST CDS_LIB mstr_standard
J 0
(-3425 3950);
DISPLAY 0.723404 (-3425 3950);
PAINT MONO (-3425 3950);
DISPLAY INVISIBLE (-3425 3950);
FORCEPROP 1 LAST BODY_TYPE PLUMBING
J 0
(-3425 4000);
DISPLAY 0.872340 (-3425 4000);
PAINT GREEN (-3425 4000);
DISPLAY INVISIBLE (-3425 4000);
FORCEPROP 1 LAST HDL_TAP TRUE
J 0
(-3100 3825);
DISPLAY 0.872340 (-3100 3825);
DISPLAY INVISIBLE (-3100 3825);
FORCEPROP 1 LAST PATH I209
J 0
(-3427 3950);
DISPLAY 0.872340 (-3427 3950);
PAINT GREEN (-3427 3950);
DISPLAY INVISIBLE (-3427 3950);
FORCEADD TAP..1
(-3425 3900);
FORCEPROP 3 LASTPIN (-3475 3900) SIG_NAME M_G_CPU1_SB_DQ<7>
J 0
(-3465 3910);
DISPLAY 0.659574 (-3465 3910);
PAINT MONO (-3465 3910);
DISPLAY INVISIBLE (-3465 3910);
FORCEPROP 1 LASTPIN (-3475 3900) BN 7
J 0
(-3487 3908);
DISPLAY 0.489362 (-3487 3908);
PAINT GREEN (-3487 3908);
FORCEPROP 2 LAST CDS_LIB mstr_standard
J 0
(-3425 3900);
DISPLAY 0.723404 (-3425 3900);
PAINT MONO (-3425 3900);
DISPLAY INVISIBLE (-3425 3900);
FORCEPROP 1 LAST BODY_TYPE PLUMBING
J 0
(-3425 3950);
DISPLAY 0.872340 (-3425 3950);
PAINT GREEN (-3425 3950);
DISPLAY INVISIBLE (-3425 3950);
FORCEPROP 1 LAST HDL_TAP TRUE
J 0
(-3100 3775);
DISPLAY 0.872340 (-3100 3775);
DISPLAY INVISIBLE (-3100 3775);
FORCEPROP 1 LAST PATH I210
J 0
(-3427 3900);
DISPLAY 0.872340 (-3427 3900);
PAINT GREEN (-3427 3900);
DISPLAY INVISIBLE (-3427 3900);
FORCEADD TAP..1
(-3425 3800);
FORCEPROP 3 LASTPIN (-3475 3800) SIG_NAME M_G_CPU1_SB_DQ<8>
J 0
(-3465 3810);
DISPLAY 0.659574 (-3465 3810);
PAINT MONO (-3465 3810);
DISPLAY INVISIBLE (-3465 3810);
FORCEPROP 1 LASTPIN (-3475 3800) BN 8
J 0
(-3487 3808);
DISPLAY 0.489362 (-3487 3808);
PAINT GREEN (-3487 3808);
FORCEPROP 2 LAST CDS_LIB mstr_standard
J 0
(-3425 3800);
DISPLAY 0.723404 (-3425 3800);
PAINT MONO (-3425 3800);
DISPLAY INVISIBLE (-3425 3800);
FORCEPROP 1 LAST BODY_TYPE PLUMBING
J 0
(-3425 3850);
DISPLAY 0.872340 (-3425 3850);
PAINT GREEN (-3425 3850);
DISPLAY INVISIBLE (-3425 3850);
FORCEPROP 1 LAST HDL_TAP TRUE
J 0
(-3100 3675);
DISPLAY 0.872340 (-3100 3675);
DISPLAY INVISIBLE (-3100 3675);
FORCEPROP 1 LAST PATH I211
J 0
(-3427 3800);
DISPLAY 0.872340 (-3427 3800);
PAINT GREEN (-3427 3800);
DISPLAY INVISIBLE (-3427 3800);
FORCEADD TAP..1
(-3425 3750);
FORCEPROP 3 LASTPIN (-3475 3750) SIG_NAME M_G_CPU1_SB_DQ<9>
J 0
(-3465 3760);
DISPLAY 0.659574 (-3465 3760);
PAINT MONO (-3465 3760);
DISPLAY INVISIBLE (-3465 3760);
FORCEPROP 1 LASTPIN (-3475 3750) BN 9
J 0
(-3487 3758);
DISPLAY 0.489362 (-3487 3758);
PAINT GREEN (-3487 3758);
FORCEPROP 2 LAST CDS_LIB mstr_standard
J 0
(-3425 3750);
DISPLAY 0.723404 (-3425 3750);
PAINT MONO (-3425 3750);
DISPLAY INVISIBLE (-3425 3750);
FORCEPROP 1 LAST BODY_TYPE PLUMBING
J 0
(-3425 3800);
DISPLAY 0.872340 (-3425 3800);
PAINT GREEN (-3425 3800);
DISPLAY INVISIBLE (-3425 3800);
FORCEPROP 1 LAST HDL_TAP TRUE
J 0
(-3100 3625);
DISPLAY 0.872340 (-3100 3625);
DISPLAY INVISIBLE (-3100 3625);
FORCEPROP 1 LAST PATH I212
J 0
(-3427 3750);
DISPLAY 0.872340 (-3427 3750);
PAINT GREEN (-3427 3750);
DISPLAY INVISIBLE (-3427 3750);
FORCEADD TAP..1
(-3425 3700);
FORCEPROP 3 LASTPIN (-3475 3700) SIG_NAME M_G_CPU1_SB_DQ<10>
J 0
(-3465 3710);
DISPLAY 0.659574 (-3465 3710);
PAINT MONO (-3465 3710);
DISPLAY INVISIBLE (-3465 3710);
FORCEPROP 1 LASTPIN (-3475 3700) BN 10
J 0
(-3487 3708);
DISPLAY 0.489362 (-3487 3708);
PAINT GREEN (-3487 3708);
FORCEPROP 2 LAST CDS_LIB mstr_standard
J 0
(-3425 3700);
DISPLAY 0.723404 (-3425 3700);
PAINT MONO (-3425 3700);
DISPLAY INVISIBLE (-3425 3700);
FORCEPROP 1 LAST BODY_TYPE PLUMBING
J 0
(-3425 3750);
DISPLAY 0.872340 (-3425 3750);
PAINT GREEN (-3425 3750);
DISPLAY INVISIBLE (-3425 3750);
FORCEPROP 1 LAST HDL_TAP TRUE
J 0
(-3100 3575);
DISPLAY 0.872340 (-3100 3575);
DISPLAY INVISIBLE (-3100 3575);
FORCEPROP 1 LAST PATH I213
J 0
(-3427 3700);
DISPLAY 0.872340 (-3427 3700);
PAINT GREEN (-3427 3700);
DISPLAY INVISIBLE (-3427 3700);
FORCEADD TAP..1
(-3425 3650);
FORCEPROP 3 LASTPIN (-3475 3650) SIG_NAME M_G_CPU1_SB_DQ<11>
J 0
(-3465 3660);
DISPLAY 0.659574 (-3465 3660);
PAINT MONO (-3465 3660);
DISPLAY INVISIBLE (-3465 3660);
FORCEPROP 1 LASTPIN (-3475 3650) BN 11
J 0
(-3487 3658);
DISPLAY 0.489362 (-3487 3658);
PAINT GREEN (-3487 3658);
FORCEPROP 2 LAST CDS_LIB mstr_standard
J 0
(-3425 3650);
DISPLAY 0.723404 (-3425 3650);
PAINT MONO (-3425 3650);
DISPLAY INVISIBLE (-3425 3650);
FORCEPROP 1 LAST BODY_TYPE PLUMBING
J 0
(-3425 3700);
DISPLAY 0.872340 (-3425 3700);
PAINT GREEN (-3425 3700);
DISPLAY INVISIBLE (-3425 3700);
FORCEPROP 1 LAST HDL_TAP TRUE
J 0
(-3100 3525);
DISPLAY 0.872340 (-3100 3525);
DISPLAY INVISIBLE (-3100 3525);
FORCEPROP 1 LAST PATH I214
J 0
(-3427 3650);
DISPLAY 0.872340 (-3427 3650);
PAINT GREEN (-3427 3650);
DISPLAY INVISIBLE (-3427 3650);
FORCEADD TAP..1
(-3425 3600);
FORCEPROP 3 LASTPIN (-3475 3600) SIG_NAME M_G_CPU1_SB_DQ<12>
J 0
(-3465 3610);
DISPLAY 0.659574 (-3465 3610);
PAINT MONO (-3465 3610);
DISPLAY INVISIBLE (-3465 3610);
FORCEPROP 1 LASTPIN (-3475 3600) BN 12
J 0
(-3487 3608);
DISPLAY 0.489362 (-3487 3608);
PAINT GREEN (-3487 3608);
FORCEPROP 2 LAST CDS_LIB mstr_standard
J 0
(-3425 3600);
DISPLAY 0.723404 (-3425 3600);
PAINT MONO (-3425 3600);
DISPLAY INVISIBLE (-3425 3600);
FORCEPROP 1 LAST BODY_TYPE PLUMBING
J 0
(-3425 3650);
DISPLAY 0.872340 (-3425 3650);
PAINT GREEN (-3425 3650);
DISPLAY INVISIBLE (-3425 3650);
FORCEPROP 1 LAST HDL_TAP TRUE
J 0
(-3100 3475);
DISPLAY 0.872340 (-3100 3475);
DISPLAY INVISIBLE (-3100 3475);
FORCEPROP 1 LAST PATH I215
J 0
(-3427 3600);
DISPLAY 0.872340 (-3427 3600);
PAINT GREEN (-3427 3600);
DISPLAY INVISIBLE (-3427 3600);
FORCEADD TAP..1
(-3425 3550);
FORCEPROP 3 LASTPIN (-3475 3550) SIG_NAME M_G_CPU1_SB_DQ<13>
J 0
(-3465 3560);
DISPLAY 0.659574 (-3465 3560);
PAINT MONO (-3465 3560);
DISPLAY INVISIBLE (-3465 3560);
FORCEPROP 1 LASTPIN (-3475 3550) BN 13
J 0
(-3487 3558);
DISPLAY 0.489362 (-3487 3558);
PAINT GREEN (-3487 3558);
FORCEPROP 2 LAST CDS_LIB mstr_standard
J 0
(-3425 3550);
DISPLAY 0.723404 (-3425 3550);
PAINT MONO (-3425 3550);
DISPLAY INVISIBLE (-3425 3550);
FORCEPROP 1 LAST BODY_TYPE PLUMBING
J 0
(-3425 3600);
DISPLAY 0.872340 (-3425 3600);
PAINT GREEN (-3425 3600);
DISPLAY INVISIBLE (-3425 3600);
FORCEPROP 1 LAST HDL_TAP TRUE
J 0
(-3100 3425);
DISPLAY 0.872340 (-3100 3425);
DISPLAY INVISIBLE (-3100 3425);
FORCEPROP 1 LAST PATH I216
J 0
(-3427 3550);
DISPLAY 0.872340 (-3427 3550);
PAINT GREEN (-3427 3550);
DISPLAY INVISIBLE (-3427 3550);
FORCEADD TAP..1
(-3425 3500);
FORCEPROP 3 LASTPIN (-3475 3500) SIG_NAME M_G_CPU1_SB_DQ<14>
J 0
(-3465 3510);
DISPLAY 0.659574 (-3465 3510);
PAINT MONO (-3465 3510);
DISPLAY INVISIBLE (-3465 3510);
FORCEPROP 1 LASTPIN (-3475 3500) BN 14
J 0
(-3487 3508);
DISPLAY 0.489362 (-3487 3508);
PAINT GREEN (-3487 3508);
FORCEPROP 2 LAST CDS_LIB mstr_standard
J 0
(-3425 3500);
DISPLAY 0.723404 (-3425 3500);
PAINT MONO (-3425 3500);
DISPLAY INVISIBLE (-3425 3500);
FORCEPROP 1 LAST BODY_TYPE PLUMBING
J 0
(-3425 3550);
DISPLAY 0.872340 (-3425 3550);
PAINT GREEN (-3425 3550);
DISPLAY INVISIBLE (-3425 3550);
FORCEPROP 1 LAST HDL_TAP TRUE
J 0
(-3100 3375);
DISPLAY 0.872340 (-3100 3375);
DISPLAY INVISIBLE (-3100 3375);
FORCEPROP 1 LAST PATH I217
J 0
(-3427 3500);
DISPLAY 0.872340 (-3427 3500);
PAINT GREEN (-3427 3500);
DISPLAY INVISIBLE (-3427 3500);
FORCEADD TAP..1
(-3425 3450);
FORCEPROP 3 LASTPIN (-3475 3450) SIG_NAME M_G_CPU1_SB_DQ<15>
J 0
(-3465 3460);
DISPLAY 0.659574 (-3465 3460);
PAINT MONO (-3465 3460);
DISPLAY INVISIBLE (-3465 3460);
FORCEPROP 1 LASTPIN (-3475 3450) BN 15
J 0
(-3487 3458);
DISPLAY 0.489362 (-3487 3458);
PAINT GREEN (-3487 3458);
FORCEPROP 2 LAST CDS_LIB mstr_standard
J 0
(-3425 3450);
DISPLAY 0.723404 (-3425 3450);
PAINT MONO (-3425 3450);
DISPLAY INVISIBLE (-3425 3450);
FORCEPROP 1 LAST BODY_TYPE PLUMBING
J 0
(-3425 3500);
DISPLAY 0.872340 (-3425 3500);
PAINT GREEN (-3425 3500);
DISPLAY INVISIBLE (-3425 3500);
FORCEPROP 1 LAST HDL_TAP TRUE
J 0
(-3100 3325);
DISPLAY 0.872340 (-3100 3325);
DISPLAY INVISIBLE (-3100 3325);
FORCEPROP 1 LAST PATH I218
J 0
(-3427 3450);
DISPLAY 0.872340 (-3427 3450);
PAINT GREEN (-3427 3450);
DISPLAY INVISIBLE (-3427 3450);
FORCEADD TAP..1
(-3425 3350);
FORCEPROP 3 LASTPIN (-3475 3350) SIG_NAME M_G_CPU1_SB_DQ<16>
J 0
(-3465 3360);
DISPLAY 0.659574 (-3465 3360);
PAINT MONO (-3465 3360);
DISPLAY INVISIBLE (-3465 3360);
FORCEPROP 1 LASTPIN (-3475 3350) BN 16
J 0
(-3487 3358);
DISPLAY 0.489362 (-3487 3358);
PAINT GREEN (-3487 3358);
FORCEPROP 2 LAST CDS_LIB mstr_standard
J 0
(-3425 3350);
DISPLAY 0.723404 (-3425 3350);
PAINT MONO (-3425 3350);
DISPLAY INVISIBLE (-3425 3350);
FORCEPROP 1 LAST BODY_TYPE PLUMBING
J 0
(-3425 3400);
DISPLAY 0.872340 (-3425 3400);
PAINT GREEN (-3425 3400);
DISPLAY INVISIBLE (-3425 3400);
FORCEPROP 1 LAST HDL_TAP TRUE
J 0
(-3100 3225);
DISPLAY 0.872340 (-3100 3225);
DISPLAY INVISIBLE (-3100 3225);
FORCEPROP 1 LAST PATH I219
J 0
(-3427 3350);
DISPLAY 0.872340 (-3427 3350);
PAINT GREEN (-3427 3350);
DISPLAY INVISIBLE (-3427 3350);
FORCEADD TAP..1
(-3425 3300);
FORCEPROP 3 LASTPIN (-3475 3300) SIG_NAME M_G_CPU1_SB_DQ<17>
J 0
(-3465 3310);
DISPLAY 0.659574 (-3465 3310);
PAINT MONO (-3465 3310);
DISPLAY INVISIBLE (-3465 3310);
FORCEPROP 1 LASTPIN (-3475 3300) BN 17
J 0
(-3487 3308);
DISPLAY 0.489362 (-3487 3308);
PAINT GREEN (-3487 3308);
FORCEPROP 2 LAST CDS_LIB mstr_standard
J 0
(-3425 3300);
DISPLAY 0.723404 (-3425 3300);
PAINT MONO (-3425 3300);
DISPLAY INVISIBLE (-3425 3300);
FORCEPROP 1 LAST BODY_TYPE PLUMBING
J 0
(-3425 3350);
DISPLAY 0.872340 (-3425 3350);
PAINT GREEN (-3425 3350);
DISPLAY INVISIBLE (-3425 3350);
FORCEPROP 1 LAST HDL_TAP TRUE
J 0
(-3100 3175);
DISPLAY 0.872340 (-3100 3175);
DISPLAY INVISIBLE (-3100 3175);
FORCEPROP 1 LAST PATH I220
J 0
(-3427 3300);
DISPLAY 0.872340 (-3427 3300);
PAINT GREEN (-3427 3300);
DISPLAY INVISIBLE (-3427 3300);
FORCEADD TAP..1
(-3425 3250);
FORCEPROP 3 LASTPIN (-3475 3250) SIG_NAME M_G_CPU1_SB_DQ<18>
J 0
(-3465 3260);
DISPLAY 0.659574 (-3465 3260);
PAINT MONO (-3465 3260);
DISPLAY INVISIBLE (-3465 3260);
FORCEPROP 1 LASTPIN (-3475 3250) BN 18
J 0
(-3487 3258);
DISPLAY 0.489362 (-3487 3258);
PAINT GREEN (-3487 3258);
FORCEPROP 2 LAST CDS_LIB mstr_standard
J 0
(-3425 3250);
DISPLAY 0.723404 (-3425 3250);
PAINT MONO (-3425 3250);
DISPLAY INVISIBLE (-3425 3250);
FORCEPROP 1 LAST BODY_TYPE PLUMBING
J 0
(-3425 3300);
DISPLAY 0.872340 (-3425 3300);
PAINT GREEN (-3425 3300);
DISPLAY INVISIBLE (-3425 3300);
FORCEPROP 1 LAST HDL_TAP TRUE
J 0
(-3100 3125);
DISPLAY 0.872340 (-3100 3125);
DISPLAY INVISIBLE (-3100 3125);
FORCEPROP 1 LAST PATH I221
J 0
(-3427 3250);
DISPLAY 0.872340 (-3427 3250);
PAINT GREEN (-3427 3250);
DISPLAY INVISIBLE (-3427 3250);
FORCEADD TAP..1
(-3425 3200);
FORCEPROP 3 LASTPIN (-3475 3200) SIG_NAME M_G_CPU1_SB_DQ<19>
J 0
(-3465 3210);
DISPLAY 0.659574 (-3465 3210);
PAINT MONO (-3465 3210);
DISPLAY INVISIBLE (-3465 3210);
FORCEPROP 1 LASTPIN (-3475 3200) BN 19
J 0
(-3487 3208);
DISPLAY 0.489362 (-3487 3208);
PAINT GREEN (-3487 3208);
FORCEPROP 2 LAST CDS_LIB mstr_standard
J 0
(-3425 3200);
DISPLAY 0.723404 (-3425 3200);
PAINT MONO (-3425 3200);
DISPLAY INVISIBLE (-3425 3200);
FORCEPROP 1 LAST BODY_TYPE PLUMBING
J 0
(-3425 3250);
DISPLAY 0.872340 (-3425 3250);
PAINT GREEN (-3425 3250);
DISPLAY INVISIBLE (-3425 3250);
FORCEPROP 1 LAST HDL_TAP TRUE
J 0
(-3100 3075);
DISPLAY 0.872340 (-3100 3075);
DISPLAY INVISIBLE (-3100 3075);
FORCEPROP 1 LAST PATH I222
J 0
(-3427 3200);
DISPLAY 0.872340 (-3427 3200);
PAINT GREEN (-3427 3200);
DISPLAY INVISIBLE (-3427 3200);
FORCEADD TAP..1
(-3425 3150);
FORCEPROP 3 LASTPIN (-3475 3150) SIG_NAME M_G_CPU1_SB_DQ<20>
J 0
(-3465 3160);
DISPLAY 0.659574 (-3465 3160);
PAINT MONO (-3465 3160);
DISPLAY INVISIBLE (-3465 3160);
FORCEPROP 1 LASTPIN (-3475 3150) BN 20
J 0
(-3487 3158);
DISPLAY 0.489362 (-3487 3158);
PAINT GREEN (-3487 3158);
FORCEPROP 2 LAST CDS_LIB mstr_standard
J 0
(-3425 3150);
DISPLAY 0.723404 (-3425 3150);
PAINT MONO (-3425 3150);
DISPLAY INVISIBLE (-3425 3150);
FORCEPROP 1 LAST BODY_TYPE PLUMBING
J 0
(-3425 3200);
DISPLAY 0.872340 (-3425 3200);
PAINT GREEN (-3425 3200);
DISPLAY INVISIBLE (-3425 3200);
FORCEPROP 1 LAST HDL_TAP TRUE
J 0
(-3100 3025);
DISPLAY 0.872340 (-3100 3025);
DISPLAY INVISIBLE (-3100 3025);
FORCEPROP 1 LAST PATH I223
J 0
(-3427 3150);
DISPLAY 0.872340 (-3427 3150);
PAINT GREEN (-3427 3150);
DISPLAY INVISIBLE (-3427 3150);
FORCEADD TAP..1
(-3425 3100);
FORCEPROP 3 LASTPIN (-3475 3100) SIG_NAME M_G_CPU1_SB_DQ<21>
J 0
(-3465 3110);
DISPLAY 0.659574 (-3465 3110);
PAINT MONO (-3465 3110);
DISPLAY INVISIBLE (-3465 3110);
FORCEPROP 1 LASTPIN (-3475 3100) BN 21
J 0
(-3487 3108);
DISPLAY 0.489362 (-3487 3108);
PAINT GREEN (-3487 3108);
FORCEPROP 2 LAST CDS_LIB mstr_standard
J 0
(-3425 3100);
DISPLAY 0.723404 (-3425 3100);
PAINT MONO (-3425 3100);
DISPLAY INVISIBLE (-3425 3100);
FORCEPROP 1 LAST BODY_TYPE PLUMBING
J 0
(-3425 3150);
DISPLAY 0.872340 (-3425 3150);
PAINT GREEN (-3425 3150);
DISPLAY INVISIBLE (-3425 3150);
FORCEPROP 1 LAST HDL_TAP TRUE
J 0
(-3100 2975);
DISPLAY 0.872340 (-3100 2975);
DISPLAY INVISIBLE (-3100 2975);
FORCEPROP 1 LAST PATH I224
J 0
(-3427 3100);
DISPLAY 0.872340 (-3427 3100);
PAINT GREEN (-3427 3100);
DISPLAY INVISIBLE (-3427 3100);
FORCEADD TAP..1
(-3425 3000);
FORCEPROP 3 LASTPIN (-3475 3000) SIG_NAME M_G_CPU1_SB_DQ<23>
J 0
(-3465 3010);
DISPLAY 0.659574 (-3465 3010);
PAINT MONO (-3465 3010);
DISPLAY INVISIBLE (-3465 3010);
FORCEPROP 1 LASTPIN (-3475 3000) BN 23
J 0
(-3487 3008);
DISPLAY 0.489362 (-3487 3008);
PAINT GREEN (-3487 3008);
FORCEPROP 2 LAST CDS_LIB mstr_standard
J 0
(-3425 3000);
DISPLAY 0.723404 (-3425 3000);
PAINT MONO (-3425 3000);
DISPLAY INVISIBLE (-3425 3000);
FORCEPROP 1 LAST BODY_TYPE PLUMBING
J 0
(-3425 3050);
DISPLAY 0.872340 (-3425 3050);
PAINT GREEN (-3425 3050);
DISPLAY INVISIBLE (-3425 3050);
FORCEPROP 1 LAST HDL_TAP TRUE
J 0
(-3100 2875);
DISPLAY 0.872340 (-3100 2875);
DISPLAY INVISIBLE (-3100 2875);
FORCEPROP 1 LAST PATH I225
J 0
(-3427 3000);
DISPLAY 0.872340 (-3427 3000);
PAINT GREEN (-3427 3000);
DISPLAY INVISIBLE (-3427 3000);
FORCEADD TAP..1
(-3425 3050);
FORCEPROP 3 LASTPIN (-3475 3050) SIG_NAME M_G_CPU1_SB_DQ<22>
J 0
(-3465 3060);
DISPLAY 0.659574 (-3465 3060);
PAINT MONO (-3465 3060);
DISPLAY INVISIBLE (-3465 3060);
FORCEPROP 1 LASTPIN (-3475 3050) BN 22
J 0
(-3487 3058);
DISPLAY 0.489362 (-3487 3058);
PAINT GREEN (-3487 3058);
FORCEPROP 2 LAST CDS_LIB mstr_standard
J 0
(-3425 3050);
DISPLAY 0.723404 (-3425 3050);
PAINT MONO (-3425 3050);
DISPLAY INVISIBLE (-3425 3050);
FORCEPROP 1 LAST BODY_TYPE PLUMBING
J 0
(-3425 3100);
DISPLAY 0.872340 (-3425 3100);
PAINT GREEN (-3425 3100);
DISPLAY INVISIBLE (-3425 3100);
FORCEPROP 1 LAST HDL_TAP TRUE
J 0
(-3100 2925);
DISPLAY 0.872340 (-3100 2925);
DISPLAY INVISIBLE (-3100 2925);
FORCEPROP 1 LAST PATH I226
J 0
(-3427 3050);
DISPLAY 0.872340 (-3427 3050);
PAINT GREEN (-3427 3050);
DISPLAY INVISIBLE (-3427 3050);
FORCEADD TAP..1
(-3425 2900);
FORCEPROP 3 LASTPIN (-3475 2900) SIG_NAME M_G_CPU1_SB_DQ<24>
J 0
(-3465 2910);
DISPLAY 0.659574 (-3465 2910);
PAINT MONO (-3465 2910);
DISPLAY INVISIBLE (-3465 2910);
FORCEPROP 1 LASTPIN (-3475 2900) BN 24
J 0
(-3487 2908);
DISPLAY 0.489362 (-3487 2908);
PAINT GREEN (-3487 2908);
FORCEPROP 2 LAST CDS_LIB mstr_standard
J 0
(-3425 2900);
DISPLAY 0.723404 (-3425 2900);
PAINT MONO (-3425 2900);
DISPLAY INVISIBLE (-3425 2900);
FORCEPROP 1 LAST BODY_TYPE PLUMBING
J 0
(-3425 2950);
DISPLAY 0.872340 (-3425 2950);
PAINT GREEN (-3425 2950);
DISPLAY INVISIBLE (-3425 2950);
FORCEPROP 1 LAST HDL_TAP TRUE
J 0
(-3100 2775);
DISPLAY 0.872340 (-3100 2775);
DISPLAY INVISIBLE (-3100 2775);
FORCEPROP 1 LAST PATH I227
J 0
(-3427 2900);
DISPLAY 0.872340 (-3427 2900);
PAINT GREEN (-3427 2900);
DISPLAY INVISIBLE (-3427 2900);
FORCEADD TAP..1
(-3425 2850);
FORCEPROP 3 LASTPIN (-3475 2850) SIG_NAME M_G_CPU1_SB_DQ<25>
J 0
(-3465 2860);
DISPLAY 0.659574 (-3465 2860);
PAINT MONO (-3465 2860);
DISPLAY INVISIBLE (-3465 2860);
FORCEPROP 1 LASTPIN (-3475 2850) BN 25
J 0
(-3487 2858);
DISPLAY 0.489362 (-3487 2858);
PAINT GREEN (-3487 2858);
FORCEPROP 2 LAST CDS_LIB mstr_standard
J 0
(-3425 2850);
DISPLAY 0.723404 (-3425 2850);
PAINT MONO (-3425 2850);
DISPLAY INVISIBLE (-3425 2850);
FORCEPROP 1 LAST BODY_TYPE PLUMBING
J 0
(-3425 2900);
DISPLAY 0.872340 (-3425 2900);
PAINT GREEN (-3425 2900);
DISPLAY INVISIBLE (-3425 2900);
FORCEPROP 1 LAST HDL_TAP TRUE
J 0
(-3100 2725);
DISPLAY 0.872340 (-3100 2725);
DISPLAY INVISIBLE (-3100 2725);
FORCEPROP 1 LAST PATH I228
J 0
(-3427 2850);
DISPLAY 0.872340 (-3427 2850);
PAINT GREEN (-3427 2850);
DISPLAY INVISIBLE (-3427 2850);
FORCEADD TAP..1
(-3425 2800);
FORCEPROP 3 LASTPIN (-3475 2800) SIG_NAME M_G_CPU1_SB_DQ<26>
J 0
(-3465 2810);
DISPLAY 0.659574 (-3465 2810);
PAINT MONO (-3465 2810);
DISPLAY INVISIBLE (-3465 2810);
FORCEPROP 1 LASTPIN (-3475 2800) BN 26
J 0
(-3487 2808);
DISPLAY 0.489362 (-3487 2808);
PAINT GREEN (-3487 2808);
FORCEPROP 2 LAST CDS_LIB mstr_standard
J 0
(-3425 2800);
DISPLAY 0.723404 (-3425 2800);
PAINT MONO (-3425 2800);
DISPLAY INVISIBLE (-3425 2800);
FORCEPROP 1 LAST BODY_TYPE PLUMBING
J 0
(-3425 2850);
DISPLAY 0.872340 (-3425 2850);
PAINT GREEN (-3425 2850);
DISPLAY INVISIBLE (-3425 2850);
FORCEPROP 1 LAST HDL_TAP TRUE
J 0
(-3100 2675);
DISPLAY 0.872340 (-3100 2675);
DISPLAY INVISIBLE (-3100 2675);
FORCEPROP 1 LAST PATH I229
J 0
(-3427 2800);
DISPLAY 0.872340 (-3427 2800);
PAINT GREEN (-3427 2800);
DISPLAY INVISIBLE (-3427 2800);
FORCEADD TAP..1
(-3425 2700);
FORCEPROP 3 LASTPIN (-3475 2700) SIG_NAME M_G_CPU1_SB_DQ<28>
J 0
(-3465 2710);
DISPLAY 0.659574 (-3465 2710);
PAINT MONO (-3465 2710);
DISPLAY INVISIBLE (-3465 2710);
FORCEPROP 1 LASTPIN (-3475 2700) BN 28
J 0
(-3487 2708);
DISPLAY 0.489362 (-3487 2708);
PAINT GREEN (-3487 2708);
FORCEPROP 2 LAST CDS_LIB mstr_standard
J 0
(-3425 2700);
DISPLAY 0.723404 (-3425 2700);
PAINT MONO (-3425 2700);
DISPLAY INVISIBLE (-3425 2700);
FORCEPROP 1 LAST BODY_TYPE PLUMBING
J 0
(-3425 2750);
DISPLAY 0.872340 (-3425 2750);
PAINT GREEN (-3425 2750);
DISPLAY INVISIBLE (-3425 2750);
FORCEPROP 1 LAST HDL_TAP TRUE
J 0
(-3100 2575);
DISPLAY 0.872340 (-3100 2575);
DISPLAY INVISIBLE (-3100 2575);
FORCEPROP 1 LAST PATH I230
J 0
(-3427 2700);
DISPLAY 0.872340 (-3427 2700);
PAINT GREEN (-3427 2700);
DISPLAY INVISIBLE (-3427 2700);
FORCEADD TAP..1
(-3425 2750);
FORCEPROP 3 LASTPIN (-3475 2750) SIG_NAME M_G_CPU1_SB_DQ<27>
J 0
(-3465 2760);
DISPLAY 0.659574 (-3465 2760);
PAINT MONO (-3465 2760);
DISPLAY INVISIBLE (-3465 2760);
FORCEPROP 1 LASTPIN (-3475 2750) BN 27
J 0
(-3487 2758);
DISPLAY 0.489362 (-3487 2758);
PAINT GREEN (-3487 2758);
FORCEPROP 2 LAST CDS_LIB mstr_standard
J 0
(-3425 2750);
DISPLAY 0.723404 (-3425 2750);
PAINT MONO (-3425 2750);
DISPLAY INVISIBLE (-3425 2750);
FORCEPROP 1 LAST BODY_TYPE PLUMBING
J 0
(-3425 2800);
DISPLAY 0.872340 (-3425 2800);
PAINT GREEN (-3425 2800);
DISPLAY INVISIBLE (-3425 2800);
FORCEPROP 1 LAST HDL_TAP TRUE
J 0
(-3100 2625);
DISPLAY 0.872340 (-3100 2625);
DISPLAY INVISIBLE (-3100 2625);
FORCEPROP 1 LAST PATH I231
J 0
(-3427 2750);
DISPLAY 0.872340 (-3427 2750);
PAINT GREEN (-3427 2750);
DISPLAY INVISIBLE (-3427 2750);
FORCEADD TAP..1
(-3425 2650);
FORCEPROP 3 LASTPIN (-3475 2650) SIG_NAME M_G_CPU1_SB_DQ<29>
J 0
(-3465 2660);
DISPLAY 0.659574 (-3465 2660);
PAINT MONO (-3465 2660);
DISPLAY INVISIBLE (-3465 2660);
FORCEPROP 1 LASTPIN (-3475 2650) BN 29
J 0
(-3487 2658);
DISPLAY 0.489362 (-3487 2658);
PAINT GREEN (-3487 2658);
FORCEPROP 2 LAST CDS_LIB mstr_standard
J 0
(-3425 2650);
DISPLAY 0.723404 (-3425 2650);
PAINT MONO (-3425 2650);
DISPLAY INVISIBLE (-3425 2650);
FORCEPROP 1 LAST BODY_TYPE PLUMBING
J 0
(-3425 2700);
DISPLAY 0.872340 (-3425 2700);
PAINT GREEN (-3425 2700);
DISPLAY INVISIBLE (-3425 2700);
FORCEPROP 1 LAST HDL_TAP TRUE
J 0
(-3100 2525);
DISPLAY 0.872340 (-3100 2525);
DISPLAY INVISIBLE (-3100 2525);
FORCEPROP 1 LAST PATH I232
J 0
(-3427 2650);
DISPLAY 0.872340 (-3427 2650);
PAINT GREEN (-3427 2650);
DISPLAY INVISIBLE (-3427 2650);
FORCEADD TAP..1
(-3425 2600);
FORCEPROP 3 LASTPIN (-3475 2600) SIG_NAME M_G_CPU1_SB_DQ<30>
J 0
(-3465 2610);
DISPLAY 0.659574 (-3465 2610);
PAINT MONO (-3465 2610);
DISPLAY INVISIBLE (-3465 2610);
FORCEPROP 1 LASTPIN (-3475 2600) BN 30
J 0
(-3487 2608);
DISPLAY 0.489362 (-3487 2608);
PAINT GREEN (-3487 2608);
FORCEPROP 2 LAST CDS_LIB mstr_standard
J 0
(-3425 2600);
DISPLAY 0.723404 (-3425 2600);
PAINT MONO (-3425 2600);
DISPLAY INVISIBLE (-3425 2600);
FORCEPROP 1 LAST BODY_TYPE PLUMBING
J 0
(-3425 2650);
DISPLAY 0.872340 (-3425 2650);
PAINT GREEN (-3425 2650);
DISPLAY INVISIBLE (-3425 2650);
FORCEPROP 1 LAST HDL_TAP TRUE
J 0
(-3100 2475);
DISPLAY 0.872340 (-3100 2475);
DISPLAY INVISIBLE (-3100 2475);
FORCEPROP 1 LAST PATH I233
J 0
(-3427 2600);
DISPLAY 0.872340 (-3427 2600);
PAINT GREEN (-3427 2600);
DISPLAY INVISIBLE (-3427 2600);
FORCEADD TAP..1
(-3425 2550);
FORCEPROP 3 LASTPIN (-3475 2550) SIG_NAME M_G_CPU1_SB_DQ<31>
J 0
(-3465 2560);
DISPLAY 0.659574 (-3465 2560);
PAINT MONO (-3465 2560);
DISPLAY INVISIBLE (-3465 2560);
FORCEPROP 1 LASTPIN (-3475 2550) BN 31
J 0
(-3487 2558);
DISPLAY 0.489362 (-3487 2558);
PAINT GREEN (-3487 2558);
FORCEPROP 2 LAST CDS_LIB mstr_standard
J 0
(-3425 2550);
DISPLAY 0.723404 (-3425 2550);
PAINT MONO (-3425 2550);
DISPLAY INVISIBLE (-3425 2550);
FORCEPROP 1 LAST BODY_TYPE PLUMBING
J 0
(-3425 2600);
DISPLAY 0.872340 (-3425 2600);
PAINT GREEN (-3425 2600);
DISPLAY INVISIBLE (-3425 2600);
FORCEPROP 1 LAST HDL_TAP TRUE
J 0
(-3100 2425);
DISPLAY 0.872340 (-3100 2425);
DISPLAY INVISIBLE (-3100 2425);
FORCEPROP 1 LAST PATH I234
J 0
(-3427 2550);
DISPLAY 0.872340 (-3427 2550);
PAINT GREEN (-3427 2550);
DISPLAY INVISIBLE (-3427 2550);
FORCEADD TAP..1
(-3425 2450);
FORCEPROP 3 LASTPIN (-3475 2450) SIG_NAME M_G_CPU1_SA_CB<0>
J 0
(-3465 2460);
DISPLAY 0.659574 (-3465 2460);
PAINT MONO (-3465 2460);
DISPLAY INVISIBLE (-3465 2460);
FORCEPROP 1 LASTPIN (-3475 2450) BN 0
J 0
(-3487 2458);
DISPLAY 0.489362 (-3487 2458);
PAINT GREEN (-3487 2458);
FORCEPROP 2 LAST CDS_LIB mstr_standard
J 2
(-3425 2450);
DISPLAY 0.723404 (-3425 2450);
PAINT MONO (-3425 2450);
DISPLAY INVISIBLE (-3425 2450);
FORCEPROP 1 LAST BODY_TYPE PLUMBING
J 0
(-3425 2500);
DISPLAY 0.872340 (-3425 2500);
PAINT GREEN (-3425 2500);
DISPLAY INVISIBLE (-3425 2500);
FORCEPROP 1 LAST HDL_TAP TRUE
J 0
(-3100 2325);
DISPLAY 0.872340 (-3100 2325);
DISPLAY INVISIBLE (-3100 2325);
FORCEPROP 1 LAST PATH I235
J 0
(-3427 2450);
DISPLAY 0.872340 (-3427 2450);
PAINT GREEN (-3427 2450);
DISPLAY INVISIBLE (-3427 2450);
FORCEADD TAP..1
(-3425 2400);
FORCEPROP 3 LASTPIN (-3475 2400) SIG_NAME M_G_CPU1_SA_CB<1>
J 0
(-3465 2410);
DISPLAY 0.659574 (-3465 2410);
PAINT MONO (-3465 2410);
DISPLAY INVISIBLE (-3465 2410);
FORCEPROP 1 LASTPIN (-3475 2400) BN 1
J 0
(-3487 2408);
DISPLAY 0.489362 (-3487 2408);
PAINT GREEN (-3487 2408);
FORCEPROP 2 LAST CDS_LIB mstr_standard
J 2
(-3425 2400);
DISPLAY 0.723404 (-3425 2400);
PAINT MONO (-3425 2400);
DISPLAY INVISIBLE (-3425 2400);
FORCEPROP 1 LAST BODY_TYPE PLUMBING
J 0
(-3425 2450);
DISPLAY 0.872340 (-3425 2450);
PAINT GREEN (-3425 2450);
DISPLAY INVISIBLE (-3425 2450);
FORCEPROP 1 LAST HDL_TAP TRUE
J 0
(-3100 2275);
DISPLAY 0.872340 (-3100 2275);
DISPLAY INVISIBLE (-3100 2275);
FORCEPROP 1 LAST PATH I236
J 0
(-3427 2400);
DISPLAY 0.872340 (-3427 2400);
PAINT GREEN (-3427 2400);
DISPLAY INVISIBLE (-3427 2400);
FORCEADD TAP..1
(-3425 2350);
FORCEPROP 3 LASTPIN (-3475 2350) SIG_NAME M_G_CPU1_SA_CB<2>
J 0
(-3465 2360);
DISPLAY 0.659574 (-3465 2360);
PAINT MONO (-3465 2360);
DISPLAY INVISIBLE (-3465 2360);
FORCEPROP 1 LASTPIN (-3475 2350) BN 2
J 0
(-3487 2358);
DISPLAY 0.489362 (-3487 2358);
PAINT GREEN (-3487 2358);
FORCEPROP 2 LAST CDS_LIB mstr_standard
J 2
(-3425 2350);
DISPLAY 0.723404 (-3425 2350);
PAINT MONO (-3425 2350);
DISPLAY INVISIBLE (-3425 2350);
FORCEPROP 1 LAST BODY_TYPE PLUMBING
J 0
(-3425 2400);
DISPLAY 0.872340 (-3425 2400);
PAINT GREEN (-3425 2400);
DISPLAY INVISIBLE (-3425 2400);
FORCEPROP 1 LAST HDL_TAP TRUE
J 0
(-3100 2225);
DISPLAY 0.872340 (-3100 2225);
DISPLAY INVISIBLE (-3100 2225);
FORCEPROP 1 LAST PATH I237
J 0
(-3427 2350);
DISPLAY 0.872340 (-3427 2350);
PAINT GREEN (-3427 2350);
DISPLAY INVISIBLE (-3427 2350);
FORCEADD TAP..1
(-3425 2300);
FORCEPROP 3 LASTPIN (-3475 2300) SIG_NAME M_G_CPU1_SA_CB<3>
J 0
(-3465 2310);
DISPLAY 0.659574 (-3465 2310);
PAINT MONO (-3465 2310);
DISPLAY INVISIBLE (-3465 2310);
FORCEPROP 1 LASTPIN (-3475 2300) BN 3
J 0
(-3487 2308);
DISPLAY 0.489362 (-3487 2308);
PAINT GREEN (-3487 2308);
FORCEPROP 2 LAST CDS_LIB mstr_standard
J 2
(-3425 2300);
DISPLAY 0.723404 (-3425 2300);
PAINT MONO (-3425 2300);
DISPLAY INVISIBLE (-3425 2300);
FORCEPROP 1 LAST BODY_TYPE PLUMBING
J 0
(-3425 2350);
DISPLAY 0.872340 (-3425 2350);
PAINT GREEN (-3425 2350);
DISPLAY INVISIBLE (-3425 2350);
FORCEPROP 1 LAST HDL_TAP TRUE
J 0
(-3100 2175);
DISPLAY 0.872340 (-3100 2175);
DISPLAY INVISIBLE (-3100 2175);
FORCEPROP 1 LAST PATH I238
J 0
(-3427 2300);
DISPLAY 0.872340 (-3427 2300);
PAINT GREEN (-3427 2300);
DISPLAY INVISIBLE (-3427 2300);
FORCEADD TAP..1
(-3425 2250);
FORCEPROP 3 LASTPIN (-3475 2250) SIG_NAME M_G_CPU1_SA_CB<4>
J 0
(-3465 2260);
DISPLAY 0.659574 (-3465 2260);
PAINT MONO (-3465 2260);
DISPLAY INVISIBLE (-3465 2260);
FORCEPROP 1 LASTPIN (-3475 2250) BN 4
J 0
(-3487 2258);
DISPLAY 0.489362 (-3487 2258);
PAINT GREEN (-3487 2258);
FORCEPROP 2 LAST CDS_LIB mstr_standard
J 2
(-3425 2250);
DISPLAY 0.723404 (-3425 2250);
PAINT MONO (-3425 2250);
DISPLAY INVISIBLE (-3425 2250);
FORCEPROP 1 LAST BODY_TYPE PLUMBING
J 0
(-3425 2300);
DISPLAY 0.872340 (-3425 2300);
PAINT GREEN (-3425 2300);
DISPLAY INVISIBLE (-3425 2300);
FORCEPROP 1 LAST HDL_TAP TRUE
J 0
(-3100 2125);
DISPLAY 0.872340 (-3100 2125);
DISPLAY INVISIBLE (-3100 2125);
FORCEPROP 1 LAST PATH I239
J 0
(-3427 2250);
DISPLAY 0.872340 (-3427 2250);
PAINT GREEN (-3427 2250);
DISPLAY INVISIBLE (-3427 2250);
FORCEADD TAP..1
(-3425 2200);
FORCEPROP 3 LASTPIN (-3475 2200) SIG_NAME M_G_CPU1_SA_CB<5>
J 0
(-3465 2210);
DISPLAY 0.659574 (-3465 2210);
PAINT MONO (-3465 2210);
DISPLAY INVISIBLE (-3465 2210);
FORCEPROP 1 LASTPIN (-3475 2200) BN 5
J 0
(-3487 2208);
DISPLAY 0.489362 (-3487 2208);
PAINT GREEN (-3487 2208);
FORCEPROP 2 LAST CDS_LIB mstr_standard
J 2
(-3425 2200);
DISPLAY 0.723404 (-3425 2200);
PAINT MONO (-3425 2200);
DISPLAY INVISIBLE (-3425 2200);
FORCEPROP 1 LAST BODY_TYPE PLUMBING
J 0
(-3425 2250);
DISPLAY 0.872340 (-3425 2250);
PAINT GREEN (-3425 2250);
DISPLAY INVISIBLE (-3425 2250);
FORCEPROP 1 LAST HDL_TAP TRUE
J 0
(-3100 2075);
DISPLAY 0.872340 (-3100 2075);
DISPLAY INVISIBLE (-3100 2075);
FORCEPROP 1 LAST PATH I240
J 0
(-3427 2200);
DISPLAY 0.872340 (-3427 2200);
PAINT GREEN (-3427 2200);
DISPLAY INVISIBLE (-3427 2200);
FORCEADD TAP..1
(-3425 2150);
FORCEPROP 3 LASTPIN (-3475 2150) SIG_NAME M_G_CPU1_SA_CB<6>
J 0
(-3465 2160);
DISPLAY 0.659574 (-3465 2160);
PAINT MONO (-3465 2160);
DISPLAY INVISIBLE (-3465 2160);
FORCEPROP 1 LASTPIN (-3475 2150) BN 6
J 0
(-3487 2158);
DISPLAY 0.489362 (-3487 2158);
PAINT GREEN (-3487 2158);
FORCEPROP 2 LAST CDS_LIB mstr_standard
J 2
(-3425 2150);
DISPLAY 0.723404 (-3425 2150);
PAINT MONO (-3425 2150);
DISPLAY INVISIBLE (-3425 2150);
FORCEPROP 1 LAST BODY_TYPE PLUMBING
J 0
(-3425 2200);
DISPLAY 0.872340 (-3425 2200);
PAINT GREEN (-3425 2200);
DISPLAY INVISIBLE (-3425 2200);
FORCEPROP 1 LAST HDL_TAP TRUE
J 0
(-3100 2025);
DISPLAY 0.872340 (-3100 2025);
DISPLAY INVISIBLE (-3100 2025);
FORCEPROP 1 LAST PATH I241
J 0
(-3427 2150);
DISPLAY 0.872340 (-3427 2150);
PAINT GREEN (-3427 2150);
DISPLAY INVISIBLE (-3427 2150);
FORCEADD TAP..1
(-3425 2100);
FORCEPROP 3 LASTPIN (-3475 2100) SIG_NAME M_G_CPU1_SA_CB<7>
J 0
(-3465 2110);
DISPLAY 0.659574 (-3465 2110);
PAINT MONO (-3465 2110);
DISPLAY INVISIBLE (-3465 2110);
FORCEPROP 1 LASTPIN (-3475 2100) BN 7
J 0
(-3487 2108);
DISPLAY 0.489362 (-3487 2108);
PAINT GREEN (-3487 2108);
FORCEPROP 2 LAST CDS_LIB mstr_standard
J 2
(-3425 2100);
DISPLAY 0.723404 (-3425 2100);
PAINT MONO (-3425 2100);
DISPLAY INVISIBLE (-3425 2100);
FORCEPROP 1 LAST BODY_TYPE PLUMBING
J 0
(-3425 2150);
DISPLAY 0.872340 (-3425 2150);
PAINT GREEN (-3425 2150);
DISPLAY INVISIBLE (-3425 2150);
FORCEPROP 1 LAST HDL_TAP TRUE
J 0
(-3100 1975);
DISPLAY 0.872340 (-3100 1975);
DISPLAY INVISIBLE (-3100 1975);
FORCEPROP 1 LAST PATH I242
J 0
(-3427 2100);
DISPLAY 0.872340 (-3427 2100);
PAINT GREEN (-3427 2100);
DISPLAY INVISIBLE (-3427 2100);
FORCEADD OFFPAGE..6
R 2
(-2825 2050);
FORCEPROP 2 LAST $XR0 103 
J 0
(-2611 2050);
DISPLAY 0.638298 (-2611 2050);
PAINT MONO (-2611 2050);
FORCEPROP 2 LAST PATH I243
J 0
(-2600 2100);
DISPLAY 1.021277 (-2600 2100);
DISPLAY INVISIBLE (-2600 2100);
FORCEPROP 1 LAST COMMENT_BODY TRUE
J 2
(-2925 1975);
DISPLAY 0.872340 (-2925 1975);
PAINT GREEN (-2925 1975);
DISPLAY INVISIBLE (-2925 1975);
FORCEPROP 1 LAST OFFPAGE TRUE
J 2
(-3150 1925);
DISPLAY 0.872340 (-3150 1925);
PAINT GREEN (-3150 1925);
DISPLAY INVISIBLE (-3150 1925);
FORCEPROP 2 LAST CDS_LIB mstr_standard
J 2
(-2825 2050);
DISPLAY 0.723404 (-2825 2050);
PAINT MONO (-2825 2050);
DISPLAY INVISIBLE (-2825 2050);
FORCEADD TAP..1
(-3425 1950);
FORCEPROP 3 LASTPIN (-3475 1950) SIG_NAME M_G_CPU1_SB_CB<1>
J 0
(-3465 1960);
DISPLAY 0.659574 (-3465 1960);
PAINT MONO (-3465 1960);
DISPLAY INVISIBLE (-3465 1960);
FORCEPROP 1 LASTPIN (-3475 1950) BN 1
J 0
(-3487 1958);
DISPLAY 0.489362 (-3487 1958);
PAINT GREEN (-3487 1958);
FORCEPROP 2 LAST CDS_LIB mstr_standard
J 2
(-3425 1950);
DISPLAY 0.723404 (-3425 1950);
PAINT MONO (-3425 1950);
DISPLAY INVISIBLE (-3425 1950);
FORCEPROP 1 LAST BODY_TYPE PLUMBING
J 0
(-3425 2000);
DISPLAY 0.872340 (-3425 2000);
PAINT GREEN (-3425 2000);
DISPLAY INVISIBLE (-3425 2000);
FORCEPROP 1 LAST HDL_TAP TRUE
J 0
(-3100 1825);
DISPLAY 0.872340 (-3100 1825);
DISPLAY INVISIBLE (-3100 1825);
FORCEPROP 1 LAST PATH I244
J 0
(-3427 1950);
DISPLAY 0.872340 (-3427 1950);
PAINT GREEN (-3427 1950);
DISPLAY INVISIBLE (-3427 1950);
FORCEADD TAP..1
(-3425 2000);
FORCEPROP 3 LASTPIN (-3475 2000) SIG_NAME M_G_CPU1_SB_CB<0>
J 0
(-3465 2010);
DISPLAY 0.659574 (-3465 2010);
PAINT MONO (-3465 2010);
DISPLAY INVISIBLE (-3465 2010);
FORCEPROP 1 LASTPIN (-3475 2000) BN 0
J 0
(-3487 2008);
DISPLAY 0.489362 (-3487 2008);
PAINT GREEN (-3487 2008);
FORCEPROP 2 LAST CDS_LIB mstr_standard
J 2
(-3425 2000);
DISPLAY 0.723404 (-3425 2000);
PAINT MONO (-3425 2000);
DISPLAY INVISIBLE (-3425 2000);
FORCEPROP 1 LAST BODY_TYPE PLUMBING
J 0
(-3425 2050);
DISPLAY 0.872340 (-3425 2050);
PAINT GREEN (-3425 2050);
DISPLAY INVISIBLE (-3425 2050);
FORCEPROP 1 LAST HDL_TAP TRUE
J 0
(-3100 1875);
DISPLAY 0.872340 (-3100 1875);
DISPLAY INVISIBLE (-3100 1875);
FORCEPROP 1 LAST PATH I245
J 0
(-3427 2000);
DISPLAY 0.872340 (-3427 2000);
PAINT GREEN (-3427 2000);
DISPLAY INVISIBLE (-3427 2000);
FORCEADD TAP..1
(-3425 1900);
FORCEPROP 3 LASTPIN (-3475 1900) SIG_NAME M_G_CPU1_SB_CB<2>
J 0
(-3465 1910);
DISPLAY 0.659574 (-3465 1910);
PAINT MONO (-3465 1910);
DISPLAY INVISIBLE (-3465 1910);
FORCEPROP 1 LASTPIN (-3475 1900) BN 2
J 0
(-3487 1908);
DISPLAY 0.489362 (-3487 1908);
PAINT GREEN (-3487 1908);
FORCEPROP 2 LAST CDS_LIB mstr_standard
J 2
(-3425 1900);
DISPLAY 0.723404 (-3425 1900);
PAINT MONO (-3425 1900);
DISPLAY INVISIBLE (-3425 1900);
FORCEPROP 1 LAST BODY_TYPE PLUMBING
J 0
(-3425 1950);
DISPLAY 0.872340 (-3425 1950);
PAINT GREEN (-3425 1950);
DISPLAY INVISIBLE (-3425 1950);
FORCEPROP 1 LAST HDL_TAP TRUE
J 0
(-3100 1775);
DISPLAY 0.872340 (-3100 1775);
DISPLAY INVISIBLE (-3100 1775);
FORCEPROP 1 LAST PATH I246
J 0
(-3427 1900);
DISPLAY 0.872340 (-3427 1900);
PAINT GREEN (-3427 1900);
DISPLAY INVISIBLE (-3427 1900);
FORCEADD TAP..1
(-3425 1800);
FORCEPROP 3 LASTPIN (-3475 1800) SIG_NAME M_G_CPU1_SB_CB<4>
J 0
(-3465 1810);
DISPLAY 0.659574 (-3465 1810);
PAINT MONO (-3465 1810);
DISPLAY INVISIBLE (-3465 1810);
FORCEPROP 1 LASTPIN (-3475 1800) BN 4
J 0
(-3487 1808);
DISPLAY 0.489362 (-3487 1808);
PAINT GREEN (-3487 1808);
FORCEPROP 2 LAST CDS_LIB mstr_standard
J 2
(-3425 1800);
DISPLAY 0.723404 (-3425 1800);
PAINT MONO (-3425 1800);
DISPLAY INVISIBLE (-3425 1800);
FORCEPROP 1 LAST BODY_TYPE PLUMBING
J 0
(-3425 1850);
DISPLAY 0.872340 (-3425 1850);
PAINT GREEN (-3425 1850);
DISPLAY INVISIBLE (-3425 1850);
FORCEPROP 1 LAST HDL_TAP TRUE
J 0
(-3100 1675);
DISPLAY 0.872340 (-3100 1675);
DISPLAY INVISIBLE (-3100 1675);
FORCEPROP 1 LAST PATH I247
J 0
(-3427 1800);
DISPLAY 0.872340 (-3427 1800);
PAINT GREEN (-3427 1800);
DISPLAY INVISIBLE (-3427 1800);
FORCEADD TAP..1
(-3425 1850);
FORCEPROP 3 LASTPIN (-3475 1850) SIG_NAME M_G_CPU1_SB_CB<3>
J 0
(-3465 1860);
DISPLAY 0.659574 (-3465 1860);
PAINT MONO (-3465 1860);
DISPLAY INVISIBLE (-3465 1860);
FORCEPROP 1 LASTPIN (-3475 1850) BN 3
J 0
(-3487 1858);
DISPLAY 0.489362 (-3487 1858);
PAINT GREEN (-3487 1858);
FORCEPROP 2 LAST CDS_LIB mstr_standard
J 2
(-3425 1850);
DISPLAY 0.723404 (-3425 1850);
PAINT MONO (-3425 1850);
DISPLAY INVISIBLE (-3425 1850);
FORCEPROP 1 LAST BODY_TYPE PLUMBING
J 0
(-3425 1900);
DISPLAY 0.872340 (-3425 1900);
PAINT GREEN (-3425 1900);
DISPLAY INVISIBLE (-3425 1900);
FORCEPROP 1 LAST HDL_TAP TRUE
J 0
(-3100 1725);
DISPLAY 0.872340 (-3100 1725);
DISPLAY INVISIBLE (-3100 1725);
FORCEPROP 1 LAST PATH I248
J 0
(-3427 1850);
DISPLAY 0.872340 (-3427 1850);
PAINT GREEN (-3427 1850);
DISPLAY INVISIBLE (-3427 1850);
FORCEADD TAP..1
(-3425 1700);
FORCEPROP 3 LASTPIN (-3475 1700) SIG_NAME M_G_CPU1_SB_CB<6>
J 0
(-3465 1710);
DISPLAY 0.659574 (-3465 1710);
PAINT MONO (-3465 1710);
DISPLAY INVISIBLE (-3465 1710);
FORCEPROP 1 LASTPIN (-3475 1700) BN 6
J 0
(-3487 1708);
DISPLAY 0.489362 (-3487 1708);
PAINT GREEN (-3487 1708);
FORCEPROP 2 LAST CDS_LIB mstr_standard
J 2
(-3425 1700);
DISPLAY 0.723404 (-3425 1700);
PAINT MONO (-3425 1700);
DISPLAY INVISIBLE (-3425 1700);
FORCEPROP 1 LAST BODY_TYPE PLUMBING
J 0
(-3425 1750);
DISPLAY 0.872340 (-3425 1750);
PAINT GREEN (-3425 1750);
DISPLAY INVISIBLE (-3425 1750);
FORCEPROP 1 LAST HDL_TAP TRUE
J 0
(-3100 1575);
DISPLAY 0.872340 (-3100 1575);
DISPLAY INVISIBLE (-3100 1575);
FORCEPROP 1 LAST PATH I249
J 0
(-3427 1700);
DISPLAY 0.872340 (-3427 1700);
PAINT GREEN (-3427 1700);
DISPLAY INVISIBLE (-3427 1700);
FORCEADD TAP..1
(-3425 1750);
FORCEPROP 3 LASTPIN (-3475 1750) SIG_NAME M_G_CPU1_SB_CB<5>
J 0
(-3465 1760);
DISPLAY 0.659574 (-3465 1760);
PAINT MONO (-3465 1760);
DISPLAY INVISIBLE (-3465 1760);
FORCEPROP 1 LASTPIN (-3475 1750) BN 5
J 0
(-3487 1758);
DISPLAY 0.489362 (-3487 1758);
PAINT GREEN (-3487 1758);
FORCEPROP 2 LAST CDS_LIB mstr_standard
J 2
(-3425 1750);
DISPLAY 0.723404 (-3425 1750);
PAINT MONO (-3425 1750);
DISPLAY INVISIBLE (-3425 1750);
FORCEPROP 1 LAST BODY_TYPE PLUMBING
J 0
(-3425 1800);
DISPLAY 0.872340 (-3425 1800);
PAINT GREEN (-3425 1800);
DISPLAY INVISIBLE (-3425 1800);
FORCEPROP 1 LAST HDL_TAP TRUE
J 0
(-3100 1625);
DISPLAY 0.872340 (-3100 1625);
DISPLAY INVISIBLE (-3100 1625);
FORCEPROP 1 LAST PATH I250
J 0
(-3427 1750);
DISPLAY 0.872340 (-3427 1750);
PAINT GREEN (-3427 1750);
DISPLAY INVISIBLE (-3427 1750);
FORCEADD TAP..1
(-3425 1650);
FORCEPROP 3 LASTPIN (-3475 1650) SIG_NAME M_G_CPU1_SB_CB<7>
J 0
(-3465 1660);
DISPLAY 0.659574 (-3465 1660);
PAINT MONO (-3465 1660);
DISPLAY INVISIBLE (-3465 1660);
FORCEPROP 1 LASTPIN (-3475 1650) BN 7
J 0
(-3487 1658);
DISPLAY 0.489362 (-3487 1658);
PAINT GREEN (-3487 1658);
FORCEPROP 2 LAST CDS_LIB mstr_standard
J 2
(-3425 1650);
DISPLAY 0.723404 (-3425 1650);
PAINT MONO (-3425 1650);
DISPLAY INVISIBLE (-3425 1650);
FORCEPROP 1 LAST BODY_TYPE PLUMBING
J 0
(-3425 1700);
DISPLAY 0.872340 (-3425 1700);
PAINT GREEN (-3425 1700);
DISPLAY INVISIBLE (-3425 1700);
FORCEPROP 1 LAST HDL_TAP TRUE
J 0
(-3100 1525);
DISPLAY 0.872340 (-3100 1525);
DISPLAY INVISIBLE (-3100 1525);
FORCEPROP 1 LAST PATH I251
J 0
(-3427 1650);
DISPLAY 0.872340 (-3427 1650);
PAINT GREEN (-3427 1650);
DISPLAY INVISIBLE (-3427 1650);
FORCEADD TAP..1
R 2
(-5850 6050);
FORCEPROP 3 LASTPIN (-5800 6050) SIG_NAME M_G_CPU1_SA_DQS_DP<0>
J 0
(-5790 6060);
DISPLAY 0.659574 (-5790 6060);
PAINT MONO (-5790 6060);
DISPLAY INVISIBLE (-5790 6060);
FORCEPROP 1 LASTPIN (-5800 6050) BN 0
J 2
(-5788 6058);
DISPLAY 0.489362 (-5788 6058);
PAINT GREEN (-5788 6058);
FORCEPROP 2 LAST CDS_LIB mstr_standard
J 2
(-5850 6050);
DISPLAY 0.723404 (-5850 6050);
PAINT MONO (-5850 6050);
DISPLAY INVISIBLE (-5850 6050);
FORCEPROP 1 LAST BODY_TYPE PLUMBING
J 2
(-5850 6100);
DISPLAY 0.872340 (-5850 6100);
PAINT GREEN (-5850 6100);
DISPLAY INVISIBLE (-5850 6100);
FORCEPROP 1 LAST HDL_TAP TRUE
J 2
(-6175 5925);
DISPLAY 0.872340 (-6175 5925);
DISPLAY INVISIBLE (-6175 5925);
FORCEPROP 1 LAST PATH I252
J 2
(-5848 6050);
DISPLAY 0.872340 (-5848 6050);
PAINT GREEN (-5848 6050);
DISPLAY INVISIBLE (-5848 6050);
FORCEADD TAP..1
R 2
(-5850 5950);
FORCEPROP 3 LASTPIN (-5800 5950) SIG_NAME M_G_CPU1_SA_DQS_DP<1>
J 0
(-5790 5960);
DISPLAY 0.659574 (-5790 5960);
PAINT MONO (-5790 5960);
DISPLAY INVISIBLE (-5790 5960);
FORCEPROP 1 LASTPIN (-5800 5950) BN 1
J 2
(-5788 5958);
DISPLAY 0.489362 (-5788 5958);
PAINT GREEN (-5788 5958);
FORCEPROP 2 LAST CDS_LIB mstr_standard
J 2
(-5850 5950);
DISPLAY 0.723404 (-5850 5950);
PAINT MONO (-5850 5950);
DISPLAY INVISIBLE (-5850 5950);
FORCEPROP 1 LAST BODY_TYPE PLUMBING
J 2
(-5850 6000);
DISPLAY 0.872340 (-5850 6000);
PAINT GREEN (-5850 6000);
DISPLAY INVISIBLE (-5850 6000);
FORCEPROP 1 LAST HDL_TAP TRUE
J 2
(-6175 5825);
DISPLAY 0.872340 (-6175 5825);
DISPLAY INVISIBLE (-6175 5825);
FORCEPROP 1 LAST PATH I253
J 2
(-5848 5950);
DISPLAY 0.872340 (-5848 5950);
PAINT GREEN (-5848 5950);
DISPLAY INVISIBLE (-5848 5950);
FORCEADD TAP..1
R 2
(-5850 5850);
FORCEPROP 3 LASTPIN (-5800 5850) SIG_NAME M_G_CPU1_SA_DQS_DP<2>
J 0
(-5790 5860);
DISPLAY 0.659574 (-5790 5860);
PAINT MONO (-5790 5860);
DISPLAY INVISIBLE (-5790 5860);
FORCEPROP 1 LASTPIN (-5800 5850) BN 2
J 2
(-5788 5858);
DISPLAY 0.489362 (-5788 5858);
PAINT GREEN (-5788 5858);
FORCEPROP 2 LAST CDS_LIB mstr_standard
J 2
(-5850 5850);
DISPLAY 0.723404 (-5850 5850);
PAINT MONO (-5850 5850);
DISPLAY INVISIBLE (-5850 5850);
FORCEPROP 1 LAST BODY_TYPE PLUMBING
J 2
(-5850 5900);
DISPLAY 0.872340 (-5850 5900);
PAINT GREEN (-5850 5900);
DISPLAY INVISIBLE (-5850 5900);
FORCEPROP 1 LAST HDL_TAP TRUE
J 2
(-6175 5725);
DISPLAY 0.872340 (-6175 5725);
DISPLAY INVISIBLE (-6175 5725);
FORCEPROP 1 LAST PATH I254
J 2
(-5848 5850);
DISPLAY 0.872340 (-5848 5850);
PAINT GREEN (-5848 5850);
DISPLAY INVISIBLE (-5848 5850);
FORCEADD TAP..1
R 2
(-5850 5750);
FORCEPROP 3 LASTPIN (-5800 5750) SIG_NAME M_G_CPU1_SA_DQS_DP<3>
J 0
(-5790 5760);
DISPLAY 0.659574 (-5790 5760);
PAINT MONO (-5790 5760);
DISPLAY INVISIBLE (-5790 5760);
FORCEPROP 1 LASTPIN (-5800 5750) BN 3
J 2
(-5788 5758);
DISPLAY 0.489362 (-5788 5758);
PAINT GREEN (-5788 5758);
FORCEPROP 2 LAST CDS_LIB mstr_standard
J 2
(-5850 5750);
DISPLAY 0.723404 (-5850 5750);
PAINT MONO (-5850 5750);
DISPLAY INVISIBLE (-5850 5750);
FORCEPROP 1 LAST BODY_TYPE PLUMBING
J 2
(-5850 5800);
DISPLAY 0.872340 (-5850 5800);
PAINT GREEN (-5850 5800);
DISPLAY INVISIBLE (-5850 5800);
FORCEPROP 1 LAST HDL_TAP TRUE
J 2
(-6175 5625);
DISPLAY 0.872340 (-6175 5625);
DISPLAY INVISIBLE (-6175 5625);
FORCEPROP 1 LAST PATH I255
J 2
(-5848 5750);
DISPLAY 0.872340 (-5848 5750);
PAINT GREEN (-5848 5750);
DISPLAY INVISIBLE (-5848 5750);
FORCEADD TAP..1
R 2
(-5850 5650);
FORCEPROP 3 LASTPIN (-5800 5650) SIG_NAME M_G_CPU1_SA_DQS_DP<4>
J 0
(-5790 5660);
DISPLAY 0.659574 (-5790 5660);
PAINT MONO (-5790 5660);
DISPLAY INVISIBLE (-5790 5660);
FORCEPROP 1 LASTPIN (-5800 5650) BN 4
J 2
(-5788 5658);
DISPLAY 0.489362 (-5788 5658);
PAINT GREEN (-5788 5658);
FORCEPROP 2 LAST CDS_LIB mstr_standard
J 2
(-5850 5650);
DISPLAY 0.723404 (-5850 5650);
PAINT MONO (-5850 5650);
DISPLAY INVISIBLE (-5850 5650);
FORCEPROP 1 LAST BODY_TYPE PLUMBING
J 2
(-5850 5700);
DISPLAY 0.872340 (-5850 5700);
PAINT GREEN (-5850 5700);
DISPLAY INVISIBLE (-5850 5700);
FORCEPROP 1 LAST HDL_TAP TRUE
J 2
(-6175 5525);
DISPLAY 0.872340 (-6175 5525);
DISPLAY INVISIBLE (-6175 5525);
FORCEPROP 1 LAST PATH I256
J 2
(-5848 5650);
DISPLAY 0.872340 (-5848 5650);
PAINT GREEN (-5848 5650);
DISPLAY INVISIBLE (-5848 5650);
FORCEADD TAP..1
R 2
(-6050 6000);
FORCEPROP 3 LASTPIN (-6000 6000) SIG_NAME M_G_CPU1_SA_DQS_DN<0>
J 0
(-5990 6010);
DISPLAY 0.659574 (-5990 6010);
PAINT MONO (-5990 6010);
DISPLAY INVISIBLE (-5990 6010);
FORCEPROP 1 LASTPIN (-6000 6000) BN 0
J 2
(-5988 6008);
DISPLAY 0.489362 (-5988 6008);
PAINT GREEN (-5988 6008);
FORCEPROP 2 LAST CDS_LIB mstr_standard
J 2
(-6050 6000);
DISPLAY 0.723404 (-6050 6000);
PAINT MONO (-6050 6000);
DISPLAY INVISIBLE (-6050 6000);
FORCEPROP 1 LAST BODY_TYPE PLUMBING
J 2
(-6050 6050);
DISPLAY 0.872340 (-6050 6050);
PAINT GREEN (-6050 6050);
DISPLAY INVISIBLE (-6050 6050);
FORCEPROP 1 LAST HDL_TAP TRUE
J 2
(-6375 5875);
DISPLAY 0.872340 (-6375 5875);
DISPLAY INVISIBLE (-6375 5875);
FORCEPROP 1 LAST PATH I257
J 2
(-6048 6000);
DISPLAY 0.872340 (-6048 6000);
PAINT GREEN (-6048 6000);
DISPLAY INVISIBLE (-6048 6000);
FORCEADD TAP..1
R 2
(-6050 5900);
FORCEPROP 3 LASTPIN (-6000 5900) SIG_NAME M_G_CPU1_SA_DQS_DN<1>
J 0
(-5990 5910);
DISPLAY 0.659574 (-5990 5910);
PAINT MONO (-5990 5910);
DISPLAY INVISIBLE (-5990 5910);
FORCEPROP 1 LASTPIN (-6000 5900) BN 1
J 2
(-5988 5908);
DISPLAY 0.489362 (-5988 5908);
PAINT GREEN (-5988 5908);
FORCEPROP 2 LAST CDS_LIB mstr_standard
J 2
(-6050 5900);
DISPLAY 0.723404 (-6050 5900);
PAINT MONO (-6050 5900);
DISPLAY INVISIBLE (-6050 5900);
FORCEPROP 1 LAST BODY_TYPE PLUMBING
J 2
(-6050 5950);
DISPLAY 0.872340 (-6050 5950);
PAINT GREEN (-6050 5950);
DISPLAY INVISIBLE (-6050 5950);
FORCEPROP 1 LAST HDL_TAP TRUE
J 2
(-6375 5775);
DISPLAY 0.872340 (-6375 5775);
DISPLAY INVISIBLE (-6375 5775);
FORCEPROP 1 LAST PATH I258
J 2
(-6048 5900);
DISPLAY 0.872340 (-6048 5900);
PAINT GREEN (-6048 5900);
DISPLAY INVISIBLE (-6048 5900);
FORCEADD TAP..1
R 2
(-6050 5800);
FORCEPROP 3 LASTPIN (-6000 5800) SIG_NAME M_G_CPU1_SA_DQS_DN<2>
J 0
(-5990 5810);
DISPLAY 0.659574 (-5990 5810);
PAINT MONO (-5990 5810);
DISPLAY INVISIBLE (-5990 5810);
FORCEPROP 1 LASTPIN (-6000 5800) BN 2
J 2
(-5988 5808);
DISPLAY 0.489362 (-5988 5808);
PAINT GREEN (-5988 5808);
FORCEPROP 2 LAST CDS_LIB mstr_standard
J 2
(-6050 5800);
DISPLAY 0.723404 (-6050 5800);
PAINT MONO (-6050 5800);
DISPLAY INVISIBLE (-6050 5800);
FORCEPROP 1 LAST BODY_TYPE PLUMBING
J 2
(-6050 5850);
DISPLAY 0.872340 (-6050 5850);
PAINT GREEN (-6050 5850);
DISPLAY INVISIBLE (-6050 5850);
FORCEPROP 1 LAST HDL_TAP TRUE
J 2
(-6375 5675);
DISPLAY 0.872340 (-6375 5675);
DISPLAY INVISIBLE (-6375 5675);
FORCEPROP 1 LAST PATH I259
J 2
(-6048 5800);
DISPLAY 0.872340 (-6048 5800);
PAINT GREEN (-6048 5800);
DISPLAY INVISIBLE (-6048 5800);
FORCEADD TAP..1
R 2
(-6050 5700);
FORCEPROP 3 LASTPIN (-6000 5700) SIG_NAME M_G_CPU1_SA_DQS_DN<3>
J 0
(-5990 5710);
DISPLAY 0.659574 (-5990 5710);
PAINT MONO (-5990 5710);
DISPLAY INVISIBLE (-5990 5710);
FORCEPROP 1 LASTPIN (-6000 5700) BN 3
J 2
(-5988 5708);
DISPLAY 0.489362 (-5988 5708);
PAINT GREEN (-5988 5708);
FORCEPROP 2 LAST CDS_LIB mstr_standard
J 2
(-6050 5700);
DISPLAY 0.723404 (-6050 5700);
PAINT MONO (-6050 5700);
DISPLAY INVISIBLE (-6050 5700);
FORCEPROP 1 LAST BODY_TYPE PLUMBING
J 2
(-6050 5750);
DISPLAY 0.872340 (-6050 5750);
PAINT GREEN (-6050 5750);
DISPLAY INVISIBLE (-6050 5750);
FORCEPROP 1 LAST HDL_TAP TRUE
J 2
(-6375 5575);
DISPLAY 0.872340 (-6375 5575);
DISPLAY INVISIBLE (-6375 5575);
FORCEPROP 1 LAST PATH I260
J 2
(-6048 5700);
DISPLAY 0.872340 (-6048 5700);
PAINT GREEN (-6048 5700);
DISPLAY INVISIBLE (-6048 5700);
FORCEADD TAP..1
R 2
(-5850 5550);
FORCEPROP 3 LASTPIN (-5800 5550) SIG_NAME M_G_CPU1_SA_DQS_DP<5>
J 0
(-5790 5560);
DISPLAY 0.659574 (-5790 5560);
PAINT MONO (-5790 5560);
DISPLAY INVISIBLE (-5790 5560);
FORCEPROP 1 LASTPIN (-5800 5550) BN 5
J 2
(-5788 5558);
DISPLAY 0.489362 (-5788 5558);
PAINT GREEN (-5788 5558);
FORCEPROP 2 LAST CDS_LIB mstr_standard
J 2
(-5850 5550);
DISPLAY 0.723404 (-5850 5550);
PAINT MONO (-5850 5550);
DISPLAY INVISIBLE (-5850 5550);
FORCEPROP 1 LAST BODY_TYPE PLUMBING
J 2
(-5850 5600);
DISPLAY 0.872340 (-5850 5600);
PAINT GREEN (-5850 5600);
DISPLAY INVISIBLE (-5850 5600);
FORCEPROP 1 LAST HDL_TAP TRUE
J 2
(-6175 5425);
DISPLAY 0.872340 (-6175 5425);
DISPLAY INVISIBLE (-6175 5425);
FORCEPROP 1 LAST PATH I261
J 2
(-5848 5550);
DISPLAY 0.872340 (-5848 5550);
PAINT GREEN (-5848 5550);
DISPLAY INVISIBLE (-5848 5550);
FORCEADD TAP..1
R 2
(-5850 5450);
FORCEPROP 3 LASTPIN (-5800 5450) SIG_NAME M_G_CPU1_SA_DQS_DP<6>
J 0
(-5790 5460);
DISPLAY 0.659574 (-5790 5460);
PAINT MONO (-5790 5460);
DISPLAY INVISIBLE (-5790 5460);
FORCEPROP 1 LASTPIN (-5800 5450) BN 6
J 2
(-5788 5458);
DISPLAY 0.489362 (-5788 5458);
PAINT GREEN (-5788 5458);
FORCEPROP 2 LAST CDS_LIB mstr_standard
J 2
(-5850 5450);
DISPLAY 0.723404 (-5850 5450);
PAINT MONO (-5850 5450);
DISPLAY INVISIBLE (-5850 5450);
FORCEPROP 1 LAST BODY_TYPE PLUMBING
J 2
(-5850 5500);
DISPLAY 0.872340 (-5850 5500);
PAINT GREEN (-5850 5500);
DISPLAY INVISIBLE (-5850 5500);
FORCEPROP 1 LAST HDL_TAP TRUE
J 2
(-6175 5325);
DISPLAY 0.872340 (-6175 5325);
DISPLAY INVISIBLE (-6175 5325);
FORCEPROP 1 LAST PATH I262
J 2
(-5848 5450);
DISPLAY 0.872340 (-5848 5450);
PAINT GREEN (-5848 5450);
DISPLAY INVISIBLE (-5848 5450);
FORCEADD TAP..1
R 2
(-5850 5350);
FORCEPROP 3 LASTPIN (-5800 5350) SIG_NAME M_G_CPU1_SA_DQS_DP<7>
J 0
(-5790 5360);
DISPLAY 0.659574 (-5790 5360);
PAINT MONO (-5790 5360);
DISPLAY INVISIBLE (-5790 5360);
FORCEPROP 1 LASTPIN (-5800 5350) BN 7
J 2
(-5788 5358);
DISPLAY 0.489362 (-5788 5358);
PAINT GREEN (-5788 5358);
FORCEPROP 2 LAST CDS_LIB mstr_standard
J 2
(-5850 5350);
DISPLAY 0.723404 (-5850 5350);
PAINT MONO (-5850 5350);
DISPLAY INVISIBLE (-5850 5350);
FORCEPROP 1 LAST BODY_TYPE PLUMBING
J 2
(-5850 5400);
DISPLAY 0.872340 (-5850 5400);
PAINT GREEN (-5850 5400);
DISPLAY INVISIBLE (-5850 5400);
FORCEPROP 1 LAST HDL_TAP TRUE
J 2
(-6175 5225);
DISPLAY 0.872340 (-6175 5225);
DISPLAY INVISIBLE (-6175 5225);
FORCEPROP 1 LAST PATH I263
J 2
(-5848 5350);
DISPLAY 0.872340 (-5848 5350);
PAINT GREEN (-5848 5350);
DISPLAY INVISIBLE (-5848 5350);
FORCEADD TAP..1
R 2
(-5850 5250);
FORCEPROP 3 LASTPIN (-5800 5250) SIG_NAME M_G_CPU1_SA_DQS_DP<8>
J 0
(-5790 5260);
DISPLAY 0.659574 (-5790 5260);
PAINT MONO (-5790 5260);
DISPLAY INVISIBLE (-5790 5260);
FORCEPROP 1 LASTPIN (-5800 5250) BN 8
J 2
(-5788 5258);
DISPLAY 0.489362 (-5788 5258);
PAINT GREEN (-5788 5258);
FORCEPROP 2 LAST CDS_LIB mstr_standard
J 2
(-5850 5250);
DISPLAY 0.723404 (-5850 5250);
PAINT MONO (-5850 5250);
DISPLAY INVISIBLE (-5850 5250);
FORCEPROP 1 LAST BODY_TYPE PLUMBING
J 2
(-5850 5300);
DISPLAY 0.872340 (-5850 5300);
PAINT GREEN (-5850 5300);
DISPLAY INVISIBLE (-5850 5300);
FORCEPROP 1 LAST HDL_TAP TRUE
J 2
(-6175 5125);
DISPLAY 0.872340 (-6175 5125);
DISPLAY INVISIBLE (-6175 5125);
FORCEPROP 1 LAST PATH I264
J 2
(-5848 5250);
DISPLAY 0.872340 (-5848 5250);
PAINT GREEN (-5848 5250);
DISPLAY INVISIBLE (-5848 5250);
FORCEADD TAP..1
R 2
(-5850 5150);
FORCEPROP 3 LASTPIN (-5800 5150) SIG_NAME M_G_CPU1_SA_DQS_DP<9>
J 0
(-5790 5160);
DISPLAY 0.659574 (-5790 5160);
PAINT MONO (-5790 5160);
DISPLAY INVISIBLE (-5790 5160);
FORCEPROP 1 LASTPIN (-5800 5150) BN 9
J 2
(-5788 5158);
DISPLAY 0.489362 (-5788 5158);
PAINT GREEN (-5788 5158);
FORCEPROP 2 LAST CDS_LIB mstr_standard
J 2
(-5850 5150);
DISPLAY 0.723404 (-5850 5150);
PAINT MONO (-5850 5150);
DISPLAY INVISIBLE (-5850 5150);
FORCEPROP 1 LAST BODY_TYPE PLUMBING
J 2
(-5850 5200);
DISPLAY 0.872340 (-5850 5200);
PAINT GREEN (-5850 5200);
DISPLAY INVISIBLE (-5850 5200);
FORCEPROP 1 LAST HDL_TAP TRUE
J 2
(-6175 5025);
DISPLAY 0.872340 (-6175 5025);
DISPLAY INVISIBLE (-6175 5025);
FORCEPROP 1 LAST PATH I265
J 2
(-5848 5150);
DISPLAY 0.872340 (-5848 5150);
PAINT GREEN (-5848 5150);
DISPLAY INVISIBLE (-5848 5150);
FORCEADD TAP..1
R 2
(-6050 5600);
FORCEPROP 3 LASTPIN (-6000 5600) SIG_NAME M_G_CPU1_SA_DQS_DN<4>
J 0
(-5990 5610);
DISPLAY 0.659574 (-5990 5610);
PAINT MONO (-5990 5610);
DISPLAY INVISIBLE (-5990 5610);
FORCEPROP 1 LASTPIN (-6000 5600) BN 4
J 2
(-5988 5608);
DISPLAY 0.489362 (-5988 5608);
PAINT GREEN (-5988 5608);
FORCEPROP 2 LAST CDS_LIB mstr_standard
J 2
(-6050 5600);
DISPLAY 0.723404 (-6050 5600);
PAINT MONO (-6050 5600);
DISPLAY INVISIBLE (-6050 5600);
FORCEPROP 1 LAST BODY_TYPE PLUMBING
J 2
(-6050 5650);
DISPLAY 0.872340 (-6050 5650);
PAINT GREEN (-6050 5650);
DISPLAY INVISIBLE (-6050 5650);
FORCEPROP 1 LAST HDL_TAP TRUE
J 2
(-6375 5475);
DISPLAY 0.872340 (-6375 5475);
DISPLAY INVISIBLE (-6375 5475);
FORCEPROP 1 LAST PATH I266
J 2
(-6048 5600);
DISPLAY 0.872340 (-6048 5600);
PAINT GREEN (-6048 5600);
DISPLAY INVISIBLE (-6048 5600);
FORCEADD TAP..1
R 2
(-6050 5500);
FORCEPROP 3 LASTPIN (-6000 5500) SIG_NAME M_G_CPU1_SA_DQS_DN<5>
J 0
(-5990 5510);
DISPLAY 0.659574 (-5990 5510);
PAINT MONO (-5990 5510);
DISPLAY INVISIBLE (-5990 5510);
FORCEPROP 1 LASTPIN (-6000 5500) BN 5
J 2
(-5988 5508);
DISPLAY 0.489362 (-5988 5508);
PAINT GREEN (-5988 5508);
FORCEPROP 2 LAST CDS_LIB mstr_standard
J 2
(-6050 5500);
DISPLAY 0.723404 (-6050 5500);
PAINT MONO (-6050 5500);
DISPLAY INVISIBLE (-6050 5500);
FORCEPROP 1 LAST BODY_TYPE PLUMBING
J 2
(-6050 5550);
DISPLAY 0.872340 (-6050 5550);
PAINT GREEN (-6050 5550);
DISPLAY INVISIBLE (-6050 5550);
FORCEPROP 1 LAST HDL_TAP TRUE
J 2
(-6375 5375);
DISPLAY 0.872340 (-6375 5375);
DISPLAY INVISIBLE (-6375 5375);
FORCEPROP 1 LAST PATH I267
J 2
(-6048 5500);
DISPLAY 0.872340 (-6048 5500);
PAINT GREEN (-6048 5500);
DISPLAY INVISIBLE (-6048 5500);
FORCEADD TAP..1
R 2
(-6050 5400);
FORCEPROP 3 LASTPIN (-6000 5400) SIG_NAME M_G_CPU1_SA_DQS_DN<6>
J 0
(-5990 5410);
DISPLAY 0.659574 (-5990 5410);
PAINT MONO (-5990 5410);
DISPLAY INVISIBLE (-5990 5410);
FORCEPROP 1 LASTPIN (-6000 5400) BN 6
J 2
(-5988 5408);
DISPLAY 0.489362 (-5988 5408);
PAINT GREEN (-5988 5408);
FORCEPROP 2 LAST CDS_LIB mstr_standard
J 2
(-6050 5400);
DISPLAY 0.723404 (-6050 5400);
PAINT MONO (-6050 5400);
DISPLAY INVISIBLE (-6050 5400);
FORCEPROP 1 LAST BODY_TYPE PLUMBING
J 2
(-6050 5450);
DISPLAY 0.872340 (-6050 5450);
PAINT GREEN (-6050 5450);
DISPLAY INVISIBLE (-6050 5450);
FORCEPROP 1 LAST HDL_TAP TRUE
J 2
(-6375 5275);
DISPLAY 0.872340 (-6375 5275);
DISPLAY INVISIBLE (-6375 5275);
FORCEPROP 1 LAST PATH I268
J 2
(-6048 5400);
DISPLAY 0.872340 (-6048 5400);
PAINT GREEN (-6048 5400);
DISPLAY INVISIBLE (-6048 5400);
FORCEADD TAP..1
R 2
(-6050 5300);
FORCEPROP 3 LASTPIN (-6000 5300) SIG_NAME M_G_CPU1_SA_DQS_DN<7>
J 0
(-5990 5310);
DISPLAY 0.659574 (-5990 5310);
PAINT MONO (-5990 5310);
DISPLAY INVISIBLE (-5990 5310);
FORCEPROP 1 LASTPIN (-6000 5300) BN 7
J 2
(-5988 5308);
DISPLAY 0.489362 (-5988 5308);
PAINT GREEN (-5988 5308);
FORCEPROP 2 LAST CDS_LIB mstr_standard
J 2
(-6050 5300);
DISPLAY 0.723404 (-6050 5300);
PAINT MONO (-6050 5300);
DISPLAY INVISIBLE (-6050 5300);
FORCEPROP 1 LAST BODY_TYPE PLUMBING
J 2
(-6050 5350);
DISPLAY 0.872340 (-6050 5350);
PAINT GREEN (-6050 5350);
DISPLAY INVISIBLE (-6050 5350);
FORCEPROP 1 LAST HDL_TAP TRUE
J 2
(-6375 5175);
DISPLAY 0.872340 (-6375 5175);
DISPLAY INVISIBLE (-6375 5175);
FORCEPROP 1 LAST PATH I269
J 2
(-6048 5300);
DISPLAY 0.872340 (-6048 5300);
PAINT GREEN (-6048 5300);
DISPLAY INVISIBLE (-6048 5300);
FORCEADD TAP..1
R 2
(-6050 5200);
FORCEPROP 3 LASTPIN (-6000 5200) SIG_NAME M_G_CPU1_SA_DQS_DN<8>
J 0
(-5990 5210);
DISPLAY 0.659574 (-5990 5210);
PAINT MONO (-5990 5210);
DISPLAY INVISIBLE (-5990 5210);
FORCEPROP 1 LASTPIN (-6000 5200) BN 8
J 2
(-5988 5208);
DISPLAY 0.489362 (-5988 5208);
PAINT GREEN (-5988 5208);
FORCEPROP 2 LAST CDS_LIB mstr_standard
J 2
(-6050 5200);
DISPLAY 0.723404 (-6050 5200);
PAINT MONO (-6050 5200);
DISPLAY INVISIBLE (-6050 5200);
FORCEPROP 1 LAST BODY_TYPE PLUMBING
J 2
(-6050 5250);
DISPLAY 0.872340 (-6050 5250);
PAINT GREEN (-6050 5250);
DISPLAY INVISIBLE (-6050 5250);
FORCEPROP 1 LAST HDL_TAP TRUE
J 2
(-6375 5075);
DISPLAY 0.872340 (-6375 5075);
DISPLAY INVISIBLE (-6375 5075);
FORCEPROP 1 LAST PATH I270
J 2
(-6048 5200);
DISPLAY 0.872340 (-6048 5200);
PAINT GREEN (-6048 5200);
DISPLAY INVISIBLE (-6048 5200);
FORCEADD TAP..1
R 2
(-5850 5000);
FORCEPROP 3 LASTPIN (-5800 5000) SIG_NAME M_G_CPU1_SB_DQS_DP<0>
J 0
(-5790 5010);
DISPLAY 0.659574 (-5790 5010);
PAINT MONO (-5790 5010);
DISPLAY INVISIBLE (-5790 5010);
FORCEPROP 1 LASTPIN (-5800 5000) BN 0
J 2
(-5788 5008);
DISPLAY 0.489362 (-5788 5008);
PAINT GREEN (-5788 5008);
FORCEPROP 2 LAST CDS_LIB mstr_standard
J 2
(-5850 5000);
DISPLAY 0.723404 (-5850 5000);
PAINT MONO (-5850 5000);
DISPLAY INVISIBLE (-5850 5000);
FORCEPROP 1 LAST BODY_TYPE PLUMBING
J 2
(-5850 5050);
DISPLAY 0.872340 (-5850 5050);
PAINT GREEN (-5850 5050);
DISPLAY INVISIBLE (-5850 5050);
FORCEPROP 1 LAST HDL_TAP TRUE
J 2
(-6175 4875);
DISPLAY 0.872340 (-6175 4875);
DISPLAY INVISIBLE (-6175 4875);
FORCEPROP 1 LAST PATH I271
J 2
(-5848 5000);
DISPLAY 0.872340 (-5848 5000);
PAINT GREEN (-5848 5000);
DISPLAY INVISIBLE (-5848 5000);
FORCEADD TAP..1
R 2
(-5850 4900);
FORCEPROP 3 LASTPIN (-5800 4900) SIG_NAME M_G_CPU1_SB_DQS_DP<1>
J 0
(-5790 4910);
DISPLAY 0.659574 (-5790 4910);
PAINT MONO (-5790 4910);
DISPLAY INVISIBLE (-5790 4910);
FORCEPROP 1 LASTPIN (-5800 4900) BN 1
J 2
(-5788 4908);
DISPLAY 0.489362 (-5788 4908);
PAINT GREEN (-5788 4908);
FORCEPROP 2 LAST CDS_LIB mstr_standard
J 2
(-5850 4900);
DISPLAY 0.723404 (-5850 4900);
PAINT MONO (-5850 4900);
DISPLAY INVISIBLE (-5850 4900);
FORCEPROP 1 LAST BODY_TYPE PLUMBING
J 2
(-5850 4950);
DISPLAY 0.872340 (-5850 4950);
PAINT GREEN (-5850 4950);
DISPLAY INVISIBLE (-5850 4950);
FORCEPROP 1 LAST HDL_TAP TRUE
J 2
(-6175 4775);
DISPLAY 0.872340 (-6175 4775);
DISPLAY INVISIBLE (-6175 4775);
FORCEPROP 1 LAST PATH I272
J 2
(-5848 4900);
DISPLAY 0.872340 (-5848 4900);
PAINT GREEN (-5848 4900);
DISPLAY INVISIBLE (-5848 4900);
FORCEADD TAP..1
R 2
(-5850 4800);
FORCEPROP 3 LASTPIN (-5800 4800) SIG_NAME M_G_CPU1_SB_DQS_DP<2>
J 0
(-5790 4810);
DISPLAY 0.659574 (-5790 4810);
PAINT MONO (-5790 4810);
DISPLAY INVISIBLE (-5790 4810);
FORCEPROP 1 LASTPIN (-5800 4800) BN 2
J 2
(-5788 4808);
DISPLAY 0.489362 (-5788 4808);
PAINT GREEN (-5788 4808);
FORCEPROP 2 LAST CDS_LIB mstr_standard
J 2
(-5850 4800);
DISPLAY 0.723404 (-5850 4800);
PAINT MONO (-5850 4800);
DISPLAY INVISIBLE (-5850 4800);
FORCEPROP 1 LAST BODY_TYPE PLUMBING
J 2
(-5850 4850);
DISPLAY 0.872340 (-5850 4850);
PAINT GREEN (-5850 4850);
DISPLAY INVISIBLE (-5850 4850);
FORCEPROP 1 LAST HDL_TAP TRUE
J 2
(-6175 4675);
DISPLAY 0.872340 (-6175 4675);
DISPLAY INVISIBLE (-6175 4675);
FORCEPROP 1 LAST PATH I273
J 2
(-5848 4800);
DISPLAY 0.872340 (-5848 4800);
PAINT GREEN (-5848 4800);
DISPLAY INVISIBLE (-5848 4800);
FORCEADD TAP..1
R 2
(-5850 4700);
FORCEPROP 3 LASTPIN (-5800 4700) SIG_NAME M_G_CPU1_SB_DQS_DP<3>
J 0
(-5790 4710);
DISPLAY 0.659574 (-5790 4710);
PAINT MONO (-5790 4710);
DISPLAY INVISIBLE (-5790 4710);
FORCEPROP 1 LASTPIN (-5800 4700) BN 3
J 2
(-5788 4708);
DISPLAY 0.489362 (-5788 4708);
PAINT GREEN (-5788 4708);
FORCEPROP 2 LAST CDS_LIB mstr_standard
J 2
(-5850 4700);
DISPLAY 0.723404 (-5850 4700);
PAINT MONO (-5850 4700);
DISPLAY INVISIBLE (-5850 4700);
FORCEPROP 1 LAST BODY_TYPE PLUMBING
J 2
(-5850 4750);
DISPLAY 0.872340 (-5850 4750);
PAINT GREEN (-5850 4750);
DISPLAY INVISIBLE (-5850 4750);
FORCEPROP 1 LAST HDL_TAP TRUE
J 2
(-6175 4575);
DISPLAY 0.872340 (-6175 4575);
DISPLAY INVISIBLE (-6175 4575);
FORCEPROP 1 LAST PATH I274
J 2
(-5848 4700);
DISPLAY 0.872340 (-5848 4700);
PAINT GREEN (-5848 4700);
DISPLAY INVISIBLE (-5848 4700);
FORCEADD TAP..1
R 2
(-6050 5100);
FORCEPROP 3 LASTPIN (-6000 5100) SIG_NAME M_G_CPU1_SA_DQS_DN<9>
J 0
(-5990 5110);
DISPLAY 0.659574 (-5990 5110);
PAINT MONO (-5990 5110);
DISPLAY INVISIBLE (-5990 5110);
FORCEPROP 1 LASTPIN (-6000 5100) BN 9
J 2
(-5988 5108);
DISPLAY 0.489362 (-5988 5108);
PAINT GREEN (-5988 5108);
FORCEPROP 2 LAST CDS_LIB mstr_standard
J 2
(-6050 5100);
DISPLAY 0.723404 (-6050 5100);
PAINT MONO (-6050 5100);
DISPLAY INVISIBLE (-6050 5100);
FORCEPROP 1 LAST BODY_TYPE PLUMBING
J 2
(-6050 5150);
DISPLAY 0.872340 (-6050 5150);
PAINT GREEN (-6050 5150);
DISPLAY INVISIBLE (-6050 5150);
FORCEPROP 1 LAST HDL_TAP TRUE
J 2
(-6375 4975);
DISPLAY 0.872340 (-6375 4975);
DISPLAY INVISIBLE (-6375 4975);
FORCEPROP 1 LAST PATH I275
J 2
(-6048 5100);
DISPLAY 0.872340 (-6048 5100);
PAINT GREEN (-6048 5100);
DISPLAY INVISIBLE (-6048 5100);
FORCEADD TAP..1
R 2
(-6050 4950);
FORCEPROP 3 LASTPIN (-6000 4950) SIG_NAME M_G_CPU1_SB_DQS_DN<0>
J 0
(-5990 4960);
DISPLAY 0.659574 (-5990 4960);
PAINT MONO (-5990 4960);
DISPLAY INVISIBLE (-5990 4960);
FORCEPROP 1 LASTPIN (-6000 4950) BN 0
J 2
(-5988 4958);
DISPLAY 0.489362 (-5988 4958);
PAINT GREEN (-5988 4958);
FORCEPROP 2 LAST CDS_LIB mstr_standard
J 2
(-6050 4950);
DISPLAY 0.723404 (-6050 4950);
PAINT MONO (-6050 4950);
DISPLAY INVISIBLE (-6050 4950);
FORCEPROP 1 LAST BODY_TYPE PLUMBING
J 2
(-6050 5000);
DISPLAY 0.872340 (-6050 5000);
PAINT GREEN (-6050 5000);
DISPLAY INVISIBLE (-6050 5000);
FORCEPROP 1 LAST HDL_TAP TRUE
J 2
(-6375 4825);
DISPLAY 0.872340 (-6375 4825);
DISPLAY INVISIBLE (-6375 4825);
FORCEPROP 1 LAST PATH I276
J 2
(-6048 4950);
DISPLAY 0.872340 (-6048 4950);
PAINT GREEN (-6048 4950);
DISPLAY INVISIBLE (-6048 4950);
FORCEADD TAP..1
R 2
(-6050 4850);
FORCEPROP 3 LASTPIN (-6000 4850) SIG_NAME M_G_CPU1_SB_DQS_DN<1>
J 0
(-5990 4860);
DISPLAY 0.659574 (-5990 4860);
PAINT MONO (-5990 4860);
DISPLAY INVISIBLE (-5990 4860);
FORCEPROP 1 LASTPIN (-6000 4850) BN 1
J 2
(-5988 4858);
DISPLAY 0.489362 (-5988 4858);
PAINT GREEN (-5988 4858);
FORCEPROP 2 LAST CDS_LIB mstr_standard
J 2
(-6050 4850);
DISPLAY 0.723404 (-6050 4850);
PAINT MONO (-6050 4850);
DISPLAY INVISIBLE (-6050 4850);
FORCEPROP 1 LAST BODY_TYPE PLUMBING
J 2
(-6050 4900);
DISPLAY 0.872340 (-6050 4900);
PAINT GREEN (-6050 4900);
DISPLAY INVISIBLE (-6050 4900);
FORCEPROP 1 LAST HDL_TAP TRUE
J 2
(-6375 4725);
DISPLAY 0.872340 (-6375 4725);
DISPLAY INVISIBLE (-6375 4725);
FORCEPROP 1 LAST PATH I277
J 2
(-6048 4850);
DISPLAY 0.872340 (-6048 4850);
PAINT GREEN (-6048 4850);
DISPLAY INVISIBLE (-6048 4850);
FORCEADD TAP..1
R 2
(-6050 4750);
FORCEPROP 3 LASTPIN (-6000 4750) SIG_NAME M_G_CPU1_SB_DQS_DN<2>
J 0
(-5990 4760);
DISPLAY 0.659574 (-5990 4760);
PAINT MONO (-5990 4760);
DISPLAY INVISIBLE (-5990 4760);
FORCEPROP 1 LASTPIN (-6000 4750) BN 2
J 2
(-5988 4758);
DISPLAY 0.489362 (-5988 4758);
PAINT GREEN (-5988 4758);
FORCEPROP 2 LAST CDS_LIB mstr_standard
J 2
(-6050 4750);
DISPLAY 0.723404 (-6050 4750);
PAINT MONO (-6050 4750);
DISPLAY INVISIBLE (-6050 4750);
FORCEPROP 1 LAST BODY_TYPE PLUMBING
J 2
(-6050 4800);
DISPLAY 0.872340 (-6050 4800);
PAINT GREEN (-6050 4800);
DISPLAY INVISIBLE (-6050 4800);
FORCEPROP 1 LAST HDL_TAP TRUE
J 2
(-6375 4625);
DISPLAY 0.872340 (-6375 4625);
DISPLAY INVISIBLE (-6375 4625);
FORCEPROP 1 LAST PATH I278
J 2
(-6048 4750);
DISPLAY 0.872340 (-6048 4750);
PAINT GREEN (-6048 4750);
DISPLAY INVISIBLE (-6048 4750);
FORCEADD TAP..1
R 2
(-6050 4650);
FORCEPROP 3 LASTPIN (-6000 4650) SIG_NAME M_G_CPU1_SB_DQS_DN<3>
J 0
(-5990 4660);
DISPLAY 0.659574 (-5990 4660);
PAINT MONO (-5990 4660);
DISPLAY INVISIBLE (-5990 4660);
FORCEPROP 1 LASTPIN (-6000 4650) BN 3
J 2
(-5988 4658);
DISPLAY 0.489362 (-5988 4658);
PAINT GREEN (-5988 4658);
FORCEPROP 2 LAST CDS_LIB mstr_standard
J 2
(-6050 4650);
DISPLAY 0.723404 (-6050 4650);
PAINT MONO (-6050 4650);
DISPLAY INVISIBLE (-6050 4650);
FORCEPROP 1 LAST BODY_TYPE PLUMBING
J 2
(-6050 4700);
DISPLAY 0.872340 (-6050 4700);
PAINT GREEN (-6050 4700);
DISPLAY INVISIBLE (-6050 4700);
FORCEPROP 1 LAST HDL_TAP TRUE
J 2
(-6375 4525);
DISPLAY 0.872340 (-6375 4525);
DISPLAY INVISIBLE (-6375 4525);
FORCEPROP 1 LAST PATH I279
J 2
(-6048 4650);
DISPLAY 0.872340 (-6048 4650);
PAINT GREEN (-6048 4650);
DISPLAY INVISIBLE (-6048 4650);
FORCEADD TAP..1
R 2
(-5850 4600);
FORCEPROP 3 LASTPIN (-5800 4600) SIG_NAME M_G_CPU1_SB_DQS_DP<4>
J 0
(-5790 4610);
DISPLAY 0.659574 (-5790 4610);
PAINT MONO (-5790 4610);
DISPLAY INVISIBLE (-5790 4610);
FORCEPROP 1 LASTPIN (-5800 4600) BN 4
J 2
(-5788 4608);
DISPLAY 0.489362 (-5788 4608);
PAINT GREEN (-5788 4608);
FORCEPROP 2 LAST CDS_LIB mstr_standard
J 2
(-5850 4600);
DISPLAY 0.723404 (-5850 4600);
PAINT MONO (-5850 4600);
DISPLAY INVISIBLE (-5850 4600);
FORCEPROP 1 LAST BODY_TYPE PLUMBING
J 2
(-5850 4650);
DISPLAY 0.872340 (-5850 4650);
PAINT GREEN (-5850 4650);
DISPLAY INVISIBLE (-5850 4650);
FORCEPROP 1 LAST HDL_TAP TRUE
J 2
(-6175 4475);
DISPLAY 0.872340 (-6175 4475);
DISPLAY INVISIBLE (-6175 4475);
FORCEPROP 1 LAST PATH I280
J 2
(-5848 4600);
DISPLAY 0.872340 (-5848 4600);
PAINT GREEN (-5848 4600);
DISPLAY INVISIBLE (-5848 4600);
FORCEADD TAP..1
R 2
(-5850 4500);
FORCEPROP 3 LASTPIN (-5800 4500) SIG_NAME M_G_CPU1_SB_DQS_DP<5>
J 0
(-5790 4510);
DISPLAY 0.659574 (-5790 4510);
PAINT MONO (-5790 4510);
DISPLAY INVISIBLE (-5790 4510);
FORCEPROP 1 LASTPIN (-5800 4500) BN 5
J 2
(-5788 4508);
DISPLAY 0.489362 (-5788 4508);
PAINT GREEN (-5788 4508);
FORCEPROP 2 LAST CDS_LIB mstr_standard
J 2
(-5850 4500);
DISPLAY 0.723404 (-5850 4500);
PAINT MONO (-5850 4500);
DISPLAY INVISIBLE (-5850 4500);
FORCEPROP 1 LAST BODY_TYPE PLUMBING
J 2
(-5850 4550);
DISPLAY 0.872340 (-5850 4550);
PAINT GREEN (-5850 4550);
DISPLAY INVISIBLE (-5850 4550);
FORCEPROP 1 LAST HDL_TAP TRUE
J 2
(-6175 4375);
DISPLAY 0.872340 (-6175 4375);
DISPLAY INVISIBLE (-6175 4375);
FORCEPROP 1 LAST PATH I281
J 2
(-5848 4500);
DISPLAY 0.872340 (-5848 4500);
PAINT GREEN (-5848 4500);
DISPLAY INVISIBLE (-5848 4500);
FORCEADD TAP..1
R 2
(-5850 4400);
FORCEPROP 3 LASTPIN (-5800 4400) SIG_NAME M_G_CPU1_SB_DQS_DP<6>
J 0
(-5790 4410);
DISPLAY 0.659574 (-5790 4410);
PAINT MONO (-5790 4410);
DISPLAY INVISIBLE (-5790 4410);
FORCEPROP 1 LASTPIN (-5800 4400) BN 6
J 2
(-5788 4408);
DISPLAY 0.489362 (-5788 4408);
PAINT GREEN (-5788 4408);
FORCEPROP 2 LAST CDS_LIB mstr_standard
J 2
(-5850 4400);
DISPLAY 0.723404 (-5850 4400);
PAINT MONO (-5850 4400);
DISPLAY INVISIBLE (-5850 4400);
FORCEPROP 1 LAST BODY_TYPE PLUMBING
J 2
(-5850 4450);
DISPLAY 0.872340 (-5850 4450);
PAINT GREEN (-5850 4450);
DISPLAY INVISIBLE (-5850 4450);
FORCEPROP 1 LAST HDL_TAP TRUE
J 2
(-6175 4275);
DISPLAY 0.872340 (-6175 4275);
DISPLAY INVISIBLE (-6175 4275);
FORCEPROP 1 LAST PATH I282
J 2
(-5848 4400);
DISPLAY 0.872340 (-5848 4400);
PAINT GREEN (-5848 4400);
DISPLAY INVISIBLE (-5848 4400);
FORCEADD TAP..1
R 2
(-5850 4300);
FORCEPROP 3 LASTPIN (-5800 4300) SIG_NAME M_G_CPU1_SB_DQS_DP<7>
J 0
(-5790 4310);
DISPLAY 0.659574 (-5790 4310);
PAINT MONO (-5790 4310);
DISPLAY INVISIBLE (-5790 4310);
FORCEPROP 1 LASTPIN (-5800 4300) BN 7
J 2
(-5788 4308);
DISPLAY 0.489362 (-5788 4308);
PAINT GREEN (-5788 4308);
FORCEPROP 2 LAST CDS_LIB mstr_standard
J 2
(-5850 4300);
DISPLAY 0.723404 (-5850 4300);
PAINT MONO (-5850 4300);
DISPLAY INVISIBLE (-5850 4300);
FORCEPROP 1 LAST BODY_TYPE PLUMBING
J 2
(-5850 4350);
DISPLAY 0.872340 (-5850 4350);
PAINT GREEN (-5850 4350);
DISPLAY INVISIBLE (-5850 4350);
FORCEPROP 1 LAST HDL_TAP TRUE
J 2
(-6175 4175);
DISPLAY 0.872340 (-6175 4175);
DISPLAY INVISIBLE (-6175 4175);
FORCEPROP 1 LAST PATH I283
J 2
(-5848 4300);
DISPLAY 0.872340 (-5848 4300);
PAINT GREEN (-5848 4300);
DISPLAY INVISIBLE (-5848 4300);
FORCEADD TAP..1
R 2
(-5850 4200);
FORCEPROP 3 LASTPIN (-5800 4200) SIG_NAME M_G_CPU1_SB_DQS_DP<8>
J 0
(-5790 4210);
DISPLAY 0.659574 (-5790 4210);
PAINT MONO (-5790 4210);
DISPLAY INVISIBLE (-5790 4210);
FORCEPROP 1 LASTPIN (-5800 4200) BN 8
J 2
(-5788 4208);
DISPLAY 0.489362 (-5788 4208);
PAINT GREEN (-5788 4208);
FORCEPROP 2 LAST CDS_LIB mstr_standard
J 2
(-5850 4200);
DISPLAY 0.723404 (-5850 4200);
PAINT MONO (-5850 4200);
DISPLAY INVISIBLE (-5850 4200);
FORCEPROP 1 LAST BODY_TYPE PLUMBING
J 2
(-5850 4250);
DISPLAY 0.872340 (-5850 4250);
PAINT GREEN (-5850 4250);
DISPLAY INVISIBLE (-5850 4250);
FORCEPROP 1 LAST HDL_TAP TRUE
J 2
(-6175 4075);
DISPLAY 0.872340 (-6175 4075);
DISPLAY INVISIBLE (-6175 4075);
FORCEPROP 1 LAST PATH I284
J 2
(-5848 4200);
DISPLAY 0.872340 (-5848 4200);
PAINT GREEN (-5848 4200);
DISPLAY INVISIBLE (-5848 4200);
FORCEADD TAP..1
R 2
(-5850 4100);
FORCEPROP 3 LASTPIN (-5800 4100) SIG_NAME M_G_CPU1_SB_DQS_DP<9>
J 0
(-5790 4110);
DISPLAY 0.659574 (-5790 4110);
PAINT MONO (-5790 4110);
DISPLAY INVISIBLE (-5790 4110);
FORCEPROP 1 LASTPIN (-5800 4100) BN 9
J 2
(-5788 4108);
DISPLAY 0.489362 (-5788 4108);
PAINT GREEN (-5788 4108);
FORCEPROP 2 LAST CDS_LIB mstr_standard
J 2
(-5850 4100);
DISPLAY 0.723404 (-5850 4100);
PAINT MONO (-5850 4100);
DISPLAY INVISIBLE (-5850 4100);
FORCEPROP 1 LAST BODY_TYPE PLUMBING
J 2
(-5850 4150);
DISPLAY 0.872340 (-5850 4150);
PAINT GREEN (-5850 4150);
DISPLAY INVISIBLE (-5850 4150);
FORCEPROP 1 LAST HDL_TAP TRUE
J 2
(-6175 3975);
DISPLAY 0.872340 (-6175 3975);
DISPLAY INVISIBLE (-6175 3975);
FORCEPROP 1 LAST PATH I285
J 2
(-5848 4100);
DISPLAY 0.872340 (-5848 4100);
PAINT GREEN (-5848 4100);
DISPLAY INVISIBLE (-5848 4100);
FORCEADD TAP..1
R 2
(-6050 4550);
FORCEPROP 3 LASTPIN (-6000 4550) SIG_NAME M_G_CPU1_SB_DQS_DN<4>
J 0
(-5990 4560);
DISPLAY 0.659574 (-5990 4560);
PAINT MONO (-5990 4560);
DISPLAY INVISIBLE (-5990 4560);
FORCEPROP 1 LASTPIN (-6000 4550) BN 4
J 2
(-5988 4558);
DISPLAY 0.489362 (-5988 4558);
PAINT GREEN (-5988 4558);
FORCEPROP 2 LAST CDS_LIB mstr_standard
J 2
(-6050 4550);
DISPLAY 0.723404 (-6050 4550);
PAINT MONO (-6050 4550);
DISPLAY INVISIBLE (-6050 4550);
FORCEPROP 1 LAST BODY_TYPE PLUMBING
J 2
(-6050 4600);
DISPLAY 0.872340 (-6050 4600);
PAINT GREEN (-6050 4600);
DISPLAY INVISIBLE (-6050 4600);
FORCEPROP 1 LAST HDL_TAP TRUE
J 2
(-6375 4425);
DISPLAY 0.872340 (-6375 4425);
DISPLAY INVISIBLE (-6375 4425);
FORCEPROP 1 LAST PATH I286
J 2
(-6048 4550);
DISPLAY 0.872340 (-6048 4550);
PAINT GREEN (-6048 4550);
DISPLAY INVISIBLE (-6048 4550);
FORCEADD TAP..1
R 2
(-6050 4450);
FORCEPROP 3 LASTPIN (-6000 4450) SIG_NAME M_G_CPU1_SB_DQS_DN<5>
J 0
(-5990 4460);
DISPLAY 0.659574 (-5990 4460);
PAINT MONO (-5990 4460);
DISPLAY INVISIBLE (-5990 4460);
FORCEPROP 1 LASTPIN (-6000 4450) BN 5
J 2
(-5988 4458);
DISPLAY 0.489362 (-5988 4458);
PAINT GREEN (-5988 4458);
FORCEPROP 2 LAST CDS_LIB mstr_standard
J 2
(-6050 4450);
DISPLAY 0.723404 (-6050 4450);
PAINT MONO (-6050 4450);
DISPLAY INVISIBLE (-6050 4450);
FORCEPROP 1 LAST BODY_TYPE PLUMBING
J 2
(-6050 4500);
DISPLAY 0.872340 (-6050 4500);
PAINT GREEN (-6050 4500);
DISPLAY INVISIBLE (-6050 4500);
FORCEPROP 1 LAST HDL_TAP TRUE
J 2
(-6375 4325);
DISPLAY 0.872340 (-6375 4325);
DISPLAY INVISIBLE (-6375 4325);
FORCEPROP 1 LAST PATH I287
J 2
(-6048 4450);
DISPLAY 0.872340 (-6048 4450);
PAINT GREEN (-6048 4450);
DISPLAY INVISIBLE (-6048 4450);
FORCEADD TAP..1
R 2
(-6050 4350);
FORCEPROP 3 LASTPIN (-6000 4350) SIG_NAME M_G_CPU1_SB_DQS_DN<6>
J 0
(-5990 4360);
DISPLAY 0.659574 (-5990 4360);
PAINT MONO (-5990 4360);
DISPLAY INVISIBLE (-5990 4360);
FORCEPROP 1 LASTPIN (-6000 4350) BN 6
J 2
(-5988 4358);
DISPLAY 0.489362 (-5988 4358);
PAINT GREEN (-5988 4358);
FORCEPROP 2 LAST CDS_LIB mstr_standard
J 2
(-6050 4350);
DISPLAY 0.723404 (-6050 4350);
PAINT MONO (-6050 4350);
DISPLAY INVISIBLE (-6050 4350);
FORCEPROP 1 LAST BODY_TYPE PLUMBING
J 2
(-6050 4400);
DISPLAY 0.872340 (-6050 4400);
PAINT GREEN (-6050 4400);
DISPLAY INVISIBLE (-6050 4400);
FORCEPROP 1 LAST HDL_TAP TRUE
J 2
(-6375 4225);
DISPLAY 0.872340 (-6375 4225);
DISPLAY INVISIBLE (-6375 4225);
FORCEPROP 1 LAST PATH I288
J 2
(-6048 4350);
DISPLAY 0.872340 (-6048 4350);
PAINT GREEN (-6048 4350);
DISPLAY INVISIBLE (-6048 4350);
FORCEADD TAP..1
R 2
(-6050 4250);
FORCEPROP 3 LASTPIN (-6000 4250) SIG_NAME M_G_CPU1_SB_DQS_DN<7>
J 0
(-5990 4260);
DISPLAY 0.659574 (-5990 4260);
PAINT MONO (-5990 4260);
DISPLAY INVISIBLE (-5990 4260);
FORCEPROP 1 LASTPIN (-6000 4250) BN 7
J 2
(-5988 4258);
DISPLAY 0.489362 (-5988 4258);
PAINT GREEN (-5988 4258);
FORCEPROP 2 LAST CDS_LIB mstr_standard
J 2
(-6050 4250);
DISPLAY 0.723404 (-6050 4250);
PAINT MONO (-6050 4250);
DISPLAY INVISIBLE (-6050 4250);
FORCEPROP 1 LAST BODY_TYPE PLUMBING
J 2
(-6050 4300);
DISPLAY 0.872340 (-6050 4300);
PAINT GREEN (-6050 4300);
DISPLAY INVISIBLE (-6050 4300);
FORCEPROP 1 LAST HDL_TAP TRUE
J 2
(-6375 4125);
DISPLAY 0.872340 (-6375 4125);
DISPLAY INVISIBLE (-6375 4125);
FORCEPROP 1 LAST PATH I289
J 2
(-6048 4250);
DISPLAY 0.872340 (-6048 4250);
PAINT GREEN (-6048 4250);
DISPLAY INVISIBLE (-6048 4250);
FORCEADD TAP..1
R 2
(-6050 4150);
FORCEPROP 3 LASTPIN (-6000 4150) SIG_NAME M_G_CPU1_SB_DQS_DN<8>
J 0
(-5990 4160);
DISPLAY 0.659574 (-5990 4160);
PAINT MONO (-5990 4160);
DISPLAY INVISIBLE (-5990 4160);
FORCEPROP 1 LASTPIN (-6000 4150) BN 8
J 2
(-5988 4158);
DISPLAY 0.489362 (-5988 4158);
PAINT GREEN (-5988 4158);
FORCEPROP 2 LAST CDS_LIB mstr_standard
J 2
(-6050 4150);
DISPLAY 0.723404 (-6050 4150);
PAINT MONO (-6050 4150);
DISPLAY INVISIBLE (-6050 4150);
FORCEPROP 1 LAST BODY_TYPE PLUMBING
J 2
(-6050 4200);
DISPLAY 0.872340 (-6050 4200);
PAINT GREEN (-6050 4200);
DISPLAY INVISIBLE (-6050 4200);
FORCEPROP 1 LAST HDL_TAP TRUE
J 2
(-6375 4025);
DISPLAY 0.872340 (-6375 4025);
DISPLAY INVISIBLE (-6375 4025);
FORCEPROP 1 LAST PATH I290
J 2
(-6048 4150);
DISPLAY 0.872340 (-6048 4150);
PAINT GREEN (-6048 4150);
DISPLAY INVISIBLE (-6048 4150);
FORCEADD OFFPAGE..3
R 2
(-6750 6025);
FORCEPROP 2 LAST $XR0 103 
J 0
(-7030 6025);
DISPLAY 0.638298 (-7030 6025);
PAINT MONO (-7030 6025);
FORCEPROP 2 LAST PATH I291
J 0
(-7025 6075);
DISPLAY 1.021277 (-7025 6075);
DISPLAY INVISIBLE (-7025 6075);
FORCEPROP 1 LAST COMMENT_BODY TRUE
J 2
(-6700 5925);
DISPLAY 0.872340 (-6700 5925);
PAINT GREEN (-6700 5925);
DISPLAY INVISIBLE (-6700 5925);
FORCEPROP 1 LAST OFFPAGE TRUE
J 2
(-7075 5900);
DISPLAY 0.872340 (-7075 5900);
PAINT GREEN (-7075 5900);
DISPLAY INVISIBLE (-7075 5900);
FORCEPROP 2 LAST CDS_LIB standard
J 0
(-6750 6025);
DISPLAY INVISIBLE (-6750 6025);
FORCEADD OFFPAGE..3
R 2
(-6750 6075);
FORCEPROP 2 LAST $XR0 103 
J 0
(-7030 6075);
DISPLAY 0.638298 (-7030 6075);
PAINT MONO (-7030 6075);
FORCEPROP 2 LAST PATH I292
J 0
(-7025 6125);
DISPLAY 1.021277 (-7025 6125);
DISPLAY INVISIBLE (-7025 6125);
FORCEPROP 1 LAST COMMENT_BODY TRUE
J 2
(-6700 5975);
DISPLAY 0.872340 (-6700 5975);
PAINT GREEN (-6700 5975);
DISPLAY INVISIBLE (-6700 5975);
FORCEPROP 1 LAST OFFPAGE TRUE
J 2
(-7075 5950);
DISPLAY 0.872340 (-7075 5950);
PAINT GREEN (-7075 5950);
DISPLAY INVISIBLE (-7075 5950);
FORCEPROP 2 LAST CDS_LIB standard
J 0
(-6750 6075);
DISPLAY INVISIBLE (-6750 6075);
FORCEADD OFFPAGE..3
R 2
(-6750 4975);
FORCEPROP 2 LAST $XR0 103 
J 0
(-7030 4975);
DISPLAY 0.638298 (-7030 4975);
PAINT MONO (-7030 4975);
FORCEPROP 2 LAST PATH I293
J 0
(-7025 5025);
DISPLAY 1.021277 (-7025 5025);
DISPLAY INVISIBLE (-7025 5025);
FORCEPROP 1 LAST COMMENT_BODY TRUE
J 2
(-6700 4875);
DISPLAY 0.872340 (-6700 4875);
PAINT GREEN (-6700 4875);
DISPLAY INVISIBLE (-6700 4875);
FORCEPROP 1 LAST OFFPAGE TRUE
J 2
(-7075 4850);
DISPLAY 0.872340 (-7075 4850);
PAINT GREEN (-7075 4850);
DISPLAY INVISIBLE (-7075 4850);
FORCEPROP 2 LAST CDS_LIB standard
J 0
(-6750 4975);
DISPLAY INVISIBLE (-6750 4975);
FORCEADD OFFPAGE..3
R 2
(-6750 5025);
FORCEPROP 2 LAST $XR0 103 
J 0
(-7030 5025);
DISPLAY 0.638298 (-7030 5025);
PAINT MONO (-7030 5025);
FORCEPROP 2 LAST PATH I294
J 0
(-7025 5075);
DISPLAY 1.021277 (-7025 5075);
DISPLAY INVISIBLE (-7025 5075);
FORCEPROP 1 LAST COMMENT_BODY TRUE
J 2
(-6700 4925);
DISPLAY 0.872340 (-6700 4925);
PAINT GREEN (-6700 4925);
DISPLAY INVISIBLE (-6700 4925);
FORCEPROP 1 LAST OFFPAGE TRUE
J 2
(-7075 4900);
DISPLAY 0.872340 (-7075 4900);
PAINT GREEN (-7075 4900);
DISPLAY INVISIBLE (-7075 4900);
FORCEPROP 2 LAST CDS_LIB standard
J 0
(-6750 5025);
DISPLAY INVISIBLE (-6750 5025);
FORCEADD TAP..1
R 2
(-6050 4050);
FORCEPROP 3 LASTPIN (-6000 4050) SIG_NAME M_G_CPU1_SB_DQS_DN<9>
J 0
(-5990 4060);
DISPLAY 0.659574 (-5990 4060);
PAINT MONO (-5990 4060);
DISPLAY INVISIBLE (-5990 4060);
FORCEPROP 1 LASTPIN (-6000 4050) BN 9
J 2
(-5988 4058);
DISPLAY 0.489362 (-5988 4058);
PAINT GREEN (-5988 4058);
FORCEPROP 2 LAST CDS_LIB mstr_standard
J 2
(-6050 4050);
DISPLAY 0.723404 (-6050 4050);
PAINT MONO (-6050 4050);
DISPLAY INVISIBLE (-6050 4050);
FORCEPROP 1 LAST BODY_TYPE PLUMBING
J 2
(-6050 4100);
DISPLAY 0.872340 (-6050 4100);
PAINT GREEN (-6050 4100);
DISPLAY INVISIBLE (-6050 4100);
FORCEPROP 1 LAST HDL_TAP TRUE
J 2
(-6375 3925);
DISPLAY 0.872340 (-6375 3925);
DISPLAY INVISIBLE (-6375 3925);
FORCEPROP 1 LAST PATH I295
J 2
(-6048 4050);
DISPLAY 0.872340 (-6048 4050);
PAINT GREEN (-6048 4050);
DISPLAY INVISIBLE (-6048 4050);
FORCEADD TAP..1
R 2
(-6050 3900);
FORCEPROP 3 LASTPIN (-6000 3900) SIG_NAME M_G_CPU1_SA_CA<0>
J 0
(-5990 3910);
DISPLAY 0.659574 (-5990 3910);
PAINT MONO (-5990 3910);
DISPLAY INVISIBLE (-5990 3910);
FORCEPROP 1 LASTPIN (-6000 3900) BN 0
J 2
(-5988 3908);
DISPLAY 0.489362 (-5988 3908);
PAINT GREEN (-5988 3908);
FORCEPROP 2 LAST CDS_LIB mstr_standard
J 0
(-6050 3900);
DISPLAY 0.723404 (-6050 3900);
PAINT MONO (-6050 3900);
DISPLAY INVISIBLE (-6050 3900);
FORCEPROP 1 LAST BODY_TYPE PLUMBING
J 2
(-6050 3950);
DISPLAY 0.872340 (-6050 3950);
PAINT GREEN (-6050 3950);
DISPLAY INVISIBLE (-6050 3950);
FORCEPROP 1 LAST HDL_TAP TRUE
J 2
(-6375 3775);
DISPLAY 0.872340 (-6375 3775);
DISPLAY INVISIBLE (-6375 3775);
FORCEPROP 1 LAST PATH I296
J 2
(-6048 3900);
DISPLAY 0.872340 (-6048 3900);
PAINT GREEN (-6048 3900);
DISPLAY INVISIBLE (-6048 3900);
FORCEADD TAP..1
R 2
(-6050 3850);
FORCEPROP 3 LASTPIN (-6000 3850) SIG_NAME M_G_CPU1_SA_CA<1>
J 0
(-5990 3860);
DISPLAY 0.659574 (-5990 3860);
PAINT MONO (-5990 3860);
DISPLAY INVISIBLE (-5990 3860);
FORCEPROP 1 LASTPIN (-6000 3850) BN 1
J 2
(-5988 3858);
DISPLAY 0.489362 (-5988 3858);
PAINT GREEN (-5988 3858);
FORCEPROP 2 LAST CDS_LIB mstr_standard
J 0
(-6050 3850);
DISPLAY 0.723404 (-6050 3850);
PAINT MONO (-6050 3850);
DISPLAY INVISIBLE (-6050 3850);
FORCEPROP 1 LAST BODY_TYPE PLUMBING
J 2
(-6050 3900);
DISPLAY 0.872340 (-6050 3900);
PAINT GREEN (-6050 3900);
DISPLAY INVISIBLE (-6050 3900);
FORCEPROP 1 LAST HDL_TAP TRUE
J 2
(-6375 3725);
DISPLAY 0.872340 (-6375 3725);
DISPLAY INVISIBLE (-6375 3725);
FORCEPROP 1 LAST PATH I297
J 2
(-6048 3850);
DISPLAY 0.872340 (-6048 3850);
PAINT GREEN (-6048 3850);
DISPLAY INVISIBLE (-6048 3850);
FORCEADD TAP..1
R 2
(-6050 3800);
FORCEPROP 3 LASTPIN (-6000 3800) SIG_NAME M_G_CPU1_SA_CA<2>
J 0
(-5990 3810);
DISPLAY 0.659574 (-5990 3810);
PAINT MONO (-5990 3810);
DISPLAY INVISIBLE (-5990 3810);
FORCEPROP 1 LASTPIN (-6000 3800) BN 2
J 2
(-5988 3808);
DISPLAY 0.489362 (-5988 3808);
PAINT GREEN (-5988 3808);
FORCEPROP 2 LAST CDS_LIB mstr_standard
J 0
(-6050 3800);
DISPLAY 0.723404 (-6050 3800);
PAINT MONO (-6050 3800);
DISPLAY INVISIBLE (-6050 3800);
FORCEPROP 1 LAST BODY_TYPE PLUMBING
J 2
(-6050 3850);
DISPLAY 0.872340 (-6050 3850);
PAINT GREEN (-6050 3850);
DISPLAY INVISIBLE (-6050 3850);
FORCEPROP 1 LAST HDL_TAP TRUE
J 2
(-6375 3675);
DISPLAY 0.872340 (-6375 3675);
DISPLAY INVISIBLE (-6375 3675);
FORCEPROP 1 LAST PATH I298
J 2
(-6048 3800);
DISPLAY 0.872340 (-6048 3800);
PAINT GREEN (-6048 3800);
DISPLAY INVISIBLE (-6048 3800);
FORCEADD TAP..1
R 2
(-6050 3750);
FORCEPROP 3 LASTPIN (-6000 3750) SIG_NAME M_G_CPU1_SA_CA<3>
J 0
(-5990 3760);
DISPLAY 0.659574 (-5990 3760);
PAINT MONO (-5990 3760);
DISPLAY INVISIBLE (-5990 3760);
FORCEPROP 1 LASTPIN (-6000 3750) BN 3
J 2
(-5988 3758);
DISPLAY 0.489362 (-5988 3758);
PAINT GREEN (-5988 3758);
FORCEPROP 2 LAST CDS_LIB mstr_standard
J 0
(-6050 3750);
DISPLAY 0.723404 (-6050 3750);
PAINT MONO (-6050 3750);
DISPLAY INVISIBLE (-6050 3750);
FORCEPROP 1 LAST BODY_TYPE PLUMBING
J 2
(-6050 3800);
DISPLAY 0.872340 (-6050 3800);
PAINT GREEN (-6050 3800);
DISPLAY INVISIBLE (-6050 3800);
FORCEPROP 1 LAST HDL_TAP TRUE
J 2
(-6375 3625);
DISPLAY 0.872340 (-6375 3625);
DISPLAY INVISIBLE (-6375 3625);
FORCEPROP 1 LAST PATH I299
J 2
(-6048 3750);
DISPLAY 0.872340 (-6048 3750);
PAINT GREEN (-6048 3750);
DISPLAY INVISIBLE (-6048 3750);
FORCEADD TAP..1
R 2
(-6050 3700);
FORCEPROP 3 LASTPIN (-6000 3700) SIG_NAME M_G_CPU1_SA_CA<4>
J 0
(-5990 3710);
DISPLAY 0.659574 (-5990 3710);
PAINT MONO (-5990 3710);
DISPLAY INVISIBLE (-5990 3710);
FORCEPROP 1 LASTPIN (-6000 3700) BN 4
J 2
(-5988 3708);
DISPLAY 0.489362 (-5988 3708);
PAINT GREEN (-5988 3708);
FORCEPROP 2 LAST CDS_LIB mstr_standard
J 0
(-6050 3700);
DISPLAY 0.723404 (-6050 3700);
PAINT MONO (-6050 3700);
DISPLAY INVISIBLE (-6050 3700);
FORCEPROP 1 LAST BODY_TYPE PLUMBING
J 2
(-6050 3750);
DISPLAY 0.872340 (-6050 3750);
PAINT GREEN (-6050 3750);
DISPLAY INVISIBLE (-6050 3750);
FORCEPROP 1 LAST HDL_TAP TRUE
J 2
(-6375 3575);
DISPLAY 0.872340 (-6375 3575);
DISPLAY INVISIBLE (-6375 3575);
FORCEPROP 1 LAST PATH I300
J 2
(-6048 3700);
DISPLAY 0.872340 (-6048 3700);
PAINT GREEN (-6048 3700);
DISPLAY INVISIBLE (-6048 3700);
FORCEADD TAP..1
R 2
(-6050 3650);
FORCEPROP 3 LASTPIN (-6000 3650) SIG_NAME M_G_CPU1_SA_CA<5>
J 0
(-5990 3660);
DISPLAY 0.659574 (-5990 3660);
PAINT MONO (-5990 3660);
DISPLAY INVISIBLE (-5990 3660);
FORCEPROP 1 LASTPIN (-6000 3650) BN 5
J 2
(-5988 3658);
DISPLAY 0.489362 (-5988 3658);
PAINT GREEN (-5988 3658);
FORCEPROP 2 LAST CDS_LIB mstr_standard
J 0
(-6050 3650);
DISPLAY 0.723404 (-6050 3650);
PAINT MONO (-6050 3650);
DISPLAY INVISIBLE (-6050 3650);
FORCEPROP 1 LAST BODY_TYPE PLUMBING
J 2
(-6050 3700);
DISPLAY 0.872340 (-6050 3700);
PAINT GREEN (-6050 3700);
DISPLAY INVISIBLE (-6050 3700);
FORCEPROP 1 LAST HDL_TAP TRUE
J 2
(-6375 3525);
DISPLAY 0.872340 (-6375 3525);
DISPLAY INVISIBLE (-6375 3525);
FORCEPROP 1 LAST PATH I301
J 2
(-6048 3650);
DISPLAY 0.872340 (-6048 3650);
PAINT GREEN (-6048 3650);
DISPLAY INVISIBLE (-6048 3650);
FORCEADD TAP..1
R 2
(-6050 3600);
FORCEPROP 3 LASTPIN (-6000 3600) SIG_NAME M_G_CPU1_SA_CA<6>
J 0
(-5990 3610);
DISPLAY 0.659574 (-5990 3610);
PAINT MONO (-5990 3610);
DISPLAY INVISIBLE (-5990 3610);
FORCEPROP 1 LASTPIN (-6000 3600) BN 6
J 2
(-5988 3608);
DISPLAY 0.489362 (-5988 3608);
PAINT GREEN (-5988 3608);
FORCEPROP 2 LAST CDS_LIB mstr_standard
J 0
(-6050 3600);
DISPLAY 0.723404 (-6050 3600);
PAINT MONO (-6050 3600);
DISPLAY INVISIBLE (-6050 3600);
FORCEPROP 1 LAST BODY_TYPE PLUMBING
J 2
(-6050 3650);
DISPLAY 0.872340 (-6050 3650);
PAINT GREEN (-6050 3650);
DISPLAY INVISIBLE (-6050 3650);
FORCEPROP 1 LAST HDL_TAP TRUE
J 2
(-6375 3475);
DISPLAY 0.872340 (-6375 3475);
DISPLAY INVISIBLE (-6375 3475);
FORCEPROP 1 LAST PATH I302
J 2
(-6048 3600);
DISPLAY 0.872340 (-6048 3600);
PAINT GREEN (-6048 3600);
DISPLAY INVISIBLE (-6048 3600);
FORCEADD TAP..1
R 2
(-6050 3500);
FORCEPROP 3 LASTPIN (-6000 3500) SIG_NAME M_G_CPU1_SB_CA<0>
J 0
(-5990 3510);
DISPLAY 0.659574 (-5990 3510);
PAINT MONO (-5990 3510);
DISPLAY INVISIBLE (-5990 3510);
FORCEPROP 1 LASTPIN (-6000 3500) BN 0
J 2
(-5988 3508);
DISPLAY 0.489362 (-5988 3508);
PAINT GREEN (-5988 3508);
FORCEPROP 2 LAST CDS_LIB mstr_standard
J 0
(-6050 3500);
DISPLAY 0.723404 (-6050 3500);
PAINT MONO (-6050 3500);
DISPLAY INVISIBLE (-6050 3500);
FORCEPROP 1 LAST BODY_TYPE PLUMBING
J 2
(-6050 3550);
DISPLAY 0.872340 (-6050 3550);
PAINT GREEN (-6050 3550);
DISPLAY INVISIBLE (-6050 3550);
FORCEPROP 1 LAST HDL_TAP TRUE
J 2
(-6375 3375);
DISPLAY 0.872340 (-6375 3375);
DISPLAY INVISIBLE (-6375 3375);
FORCEPROP 1 LAST PATH I303
J 2
(-6048 3500);
DISPLAY 0.872340 (-6048 3500);
PAINT GREEN (-6048 3500);
DISPLAY INVISIBLE (-6048 3500);
FORCEADD TAP..1
R 2
(-6050 3450);
FORCEPROP 3 LASTPIN (-6000 3450) SIG_NAME M_G_CPU1_SB_CA<1>
J 0
(-5990 3460);
DISPLAY 0.659574 (-5990 3460);
PAINT MONO (-5990 3460);
DISPLAY INVISIBLE (-5990 3460);
FORCEPROP 1 LASTPIN (-6000 3450) BN 1
J 2
(-5988 3458);
DISPLAY 0.489362 (-5988 3458);
PAINT GREEN (-5988 3458);
FORCEPROP 2 LAST CDS_LIB mstr_standard
J 0
(-6050 3450);
DISPLAY 0.723404 (-6050 3450);
PAINT MONO (-6050 3450);
DISPLAY INVISIBLE (-6050 3450);
FORCEPROP 1 LAST BODY_TYPE PLUMBING
J 2
(-6050 3500);
DISPLAY 0.872340 (-6050 3500);
PAINT GREEN (-6050 3500);
DISPLAY INVISIBLE (-6050 3500);
FORCEPROP 1 LAST HDL_TAP TRUE
J 2
(-6375 3325);
DISPLAY 0.872340 (-6375 3325);
DISPLAY INVISIBLE (-6375 3325);
FORCEPROP 1 LAST PATH I304
J 2
(-6048 3450);
DISPLAY 0.872340 (-6048 3450);
PAINT GREEN (-6048 3450);
DISPLAY INVISIBLE (-6048 3450);
FORCEADD TAP..1
R 2
(-6050 3400);
FORCEPROP 3 LASTPIN (-6000 3400) SIG_NAME M_G_CPU1_SB_CA<2>
J 0
(-5990 3410);
DISPLAY 0.659574 (-5990 3410);
PAINT MONO (-5990 3410);
DISPLAY INVISIBLE (-5990 3410);
FORCEPROP 1 LASTPIN (-6000 3400) BN 2
J 2
(-5988 3408);
DISPLAY 0.489362 (-5988 3408);
PAINT GREEN (-5988 3408);
FORCEPROP 2 LAST CDS_LIB mstr_standard
J 0
(-6050 3400);
DISPLAY 0.723404 (-6050 3400);
PAINT MONO (-6050 3400);
DISPLAY INVISIBLE (-6050 3400);
FORCEPROP 1 LAST BODY_TYPE PLUMBING
J 2
(-6050 3450);
DISPLAY 0.872340 (-6050 3450);
PAINT GREEN (-6050 3450);
DISPLAY INVISIBLE (-6050 3450);
FORCEPROP 1 LAST HDL_TAP TRUE
J 2
(-6375 3275);
DISPLAY 0.872340 (-6375 3275);
DISPLAY INVISIBLE (-6375 3275);
FORCEPROP 1 LAST PATH I305
J 2
(-6048 3400);
DISPLAY 0.872340 (-6048 3400);
PAINT GREEN (-6048 3400);
DISPLAY INVISIBLE (-6048 3400);
FORCEADD TAP..1
R 2
(-6050 3350);
FORCEPROP 3 LASTPIN (-6000 3350) SIG_NAME M_G_CPU1_SB_CA<3>
J 0
(-5990 3360);
DISPLAY 0.659574 (-5990 3360);
PAINT MONO (-5990 3360);
DISPLAY INVISIBLE (-5990 3360);
FORCEPROP 1 LASTPIN (-6000 3350) BN 3
J 2
(-5988 3358);
DISPLAY 0.489362 (-5988 3358);
PAINT GREEN (-5988 3358);
FORCEPROP 2 LAST CDS_LIB mstr_standard
J 0
(-6050 3350);
DISPLAY 0.723404 (-6050 3350);
PAINT MONO (-6050 3350);
DISPLAY INVISIBLE (-6050 3350);
FORCEPROP 1 LAST BODY_TYPE PLUMBING
J 2
(-6050 3400);
DISPLAY 0.872340 (-6050 3400);
PAINT GREEN (-6050 3400);
DISPLAY INVISIBLE (-6050 3400);
FORCEPROP 1 LAST HDL_TAP TRUE
J 2
(-6375 3225);
DISPLAY 0.872340 (-6375 3225);
DISPLAY INVISIBLE (-6375 3225);
FORCEPROP 1 LAST PATH I306
J 2
(-6048 3350);
DISPLAY 0.872340 (-6048 3350);
PAINT GREEN (-6048 3350);
DISPLAY INVISIBLE (-6048 3350);
FORCEADD TAP..1
R 2
(-6050 3300);
FORCEPROP 3 LASTPIN (-6000 3300) SIG_NAME M_G_CPU1_SB_CA<4>
J 0
(-5990 3310);
DISPLAY 0.659574 (-5990 3310);
PAINT MONO (-5990 3310);
DISPLAY INVISIBLE (-5990 3310);
FORCEPROP 1 LASTPIN (-6000 3300) BN 4
J 2
(-5988 3308);
DISPLAY 0.489362 (-5988 3308);
PAINT GREEN (-5988 3308);
FORCEPROP 2 LAST CDS_LIB mstr_standard
J 0
(-6050 3300);
DISPLAY 0.723404 (-6050 3300);
PAINT MONO (-6050 3300);
DISPLAY INVISIBLE (-6050 3300);
FORCEPROP 1 LAST BODY_TYPE PLUMBING
J 2
(-6050 3350);
DISPLAY 0.872340 (-6050 3350);
PAINT GREEN (-6050 3350);
DISPLAY INVISIBLE (-6050 3350);
FORCEPROP 1 LAST HDL_TAP TRUE
J 2
(-6375 3175);
DISPLAY 0.872340 (-6375 3175);
DISPLAY INVISIBLE (-6375 3175);
FORCEPROP 1 LAST PATH I307
J 2
(-6048 3300);
DISPLAY 0.872340 (-6048 3300);
PAINT GREEN (-6048 3300);
DISPLAY INVISIBLE (-6048 3300);
FORCEADD TAP..1
R 2
(-6050 3250);
FORCEPROP 3 LASTPIN (-6000 3250) SIG_NAME M_G_CPU1_SB_CA<5>
J 0
(-5990 3260);
DISPLAY 0.659574 (-5990 3260);
PAINT MONO (-5990 3260);
DISPLAY INVISIBLE (-5990 3260);
FORCEPROP 1 LASTPIN (-6000 3250) BN 5
J 2
(-5988 3258);
DISPLAY 0.489362 (-5988 3258);
PAINT GREEN (-5988 3258);
FORCEPROP 2 LAST CDS_LIB mstr_standard
J 0
(-6050 3250);
DISPLAY 0.723404 (-6050 3250);
PAINT MONO (-6050 3250);
DISPLAY INVISIBLE (-6050 3250);
FORCEPROP 1 LAST BODY_TYPE PLUMBING
J 2
(-6050 3300);
DISPLAY 0.872340 (-6050 3300);
PAINT GREEN (-6050 3300);
DISPLAY INVISIBLE (-6050 3300);
FORCEPROP 1 LAST HDL_TAP TRUE
J 2
(-6375 3125);
DISPLAY 0.872340 (-6375 3125);
DISPLAY INVISIBLE (-6375 3125);
FORCEPROP 1 LAST PATH I308
J 2
(-6048 3250);
DISPLAY 0.872340 (-6048 3250);
PAINT GREEN (-6048 3250);
DISPLAY INVISIBLE (-6048 3250);
FORCEADD TAP..1
R 2
(-6050 3200);
FORCEPROP 3 LASTPIN (-6000 3200) SIG_NAME M_G_CPU1_SB_CA<6>
J 0
(-5990 3210);
DISPLAY 0.659574 (-5990 3210);
PAINT MONO (-5990 3210);
DISPLAY INVISIBLE (-5990 3210);
FORCEPROP 1 LASTPIN (-6000 3200) BN 6
J 2
(-5988 3208);
DISPLAY 0.489362 (-5988 3208);
PAINT GREEN (-5988 3208);
FORCEPROP 2 LAST CDS_LIB mstr_standard
J 0
(-6050 3200);
DISPLAY 0.723404 (-6050 3200);
PAINT MONO (-6050 3200);
DISPLAY INVISIBLE (-6050 3200);
FORCEPROP 1 LAST BODY_TYPE PLUMBING
J 2
(-6050 3250);
DISPLAY 0.872340 (-6050 3250);
PAINT GREEN (-6050 3250);
DISPLAY INVISIBLE (-6050 3250);
FORCEPROP 1 LAST HDL_TAP TRUE
J 2
(-6375 3075);
DISPLAY 0.872340 (-6375 3075);
DISPLAY INVISIBLE (-6375 3075);
FORCEPROP 1 LAST PATH I309
J 2
(-6048 3200);
DISPLAY 0.872340 (-6048 3200);
PAINT GREEN (-6048 3200);
DISPLAY INVISIBLE (-6048 3200);
FORCEADD OFFPAGE..2
R 2
(-6650 3925);
FORCEPROP 2 LAST $XR0 103 
J 0
(-6905 3925);
DISPLAY 0.638298 (-6905 3925);
PAINT MONO (-6905 3925);
FORCEPROP 2 LAST PATH I310
J 0
(-6900 3975);
DISPLAY 1.021277 (-6900 3975);
DISPLAY INVISIBLE (-6900 3975);
FORCEPROP 1 LAST COMMENT_BODY TRUE
J 2
(-6605 3830);
DISPLAY 0.872340 (-6605 3830);
PAINT GREEN (-6605 3830);
DISPLAY INVISIBLE (-6605 3830);
FORCEPROP 1 LAST OFFPAGE TRUE
J 2
(-6975 3800);
DISPLAY 0.872340 (-6975 3800);
PAINT GREEN (-6975 3800);
DISPLAY INVISIBLE (-6975 3800);
FORCEPROP 2 LAST CDS_LIB standard
J 0
(-6650 3925);
DISPLAY INVISIBLE (-6650 3925);
FORCEADD OFFPAGE..2
R 2
(-6650 3525);
FORCEPROP 2 LAST $XR0 103 
J 0
(-6905 3525);
DISPLAY 0.638298 (-6905 3525);
PAINT MONO (-6905 3525);
FORCEPROP 2 LAST PATH I311
J 0
(-6900 3575);
DISPLAY 1.021277 (-6900 3575);
DISPLAY INVISIBLE (-6900 3575);
FORCEPROP 1 LAST COMMENT_BODY TRUE
J 2
(-6605 3430);
DISPLAY 0.872340 (-6605 3430);
PAINT GREEN (-6605 3430);
DISPLAY INVISIBLE (-6605 3430);
FORCEPROP 1 LAST OFFPAGE TRUE
J 2
(-6975 3400);
DISPLAY 0.872340 (-6975 3400);
PAINT GREEN (-6975 3400);
DISPLAY INVISIBLE (-6975 3400);
FORCEPROP 2 LAST CDS_LIB standard
J 0
(-6650 3525);
DISPLAY INVISIBLE (-6650 3525);
FORCEADD OFFPAGE..2
R 2
(-6650 3000);
FORCEPROP 2 LAST $XR0 103 
J 0
(-6905 3000);
DISPLAY 0.638298 (-6905 3000);
PAINT MONO (-6905 3000);
FORCEPROP 2 LAST PATH I312
J 0
(-6900 3050);
DISPLAY 1.021277 (-6900 3050);
DISPLAY INVISIBLE (-6900 3050);
FORCEPROP 1 LAST COMMENT_BODY TRUE
J 2
(-6605 2905);
DISPLAY 0.872340 (-6605 2905);
PAINT GREEN (-6605 2905);
DISPLAY INVISIBLE (-6605 2905);
FORCEPROP 1 LAST OFFPAGE TRUE
J 2
(-6975 2875);
DISPLAY 0.872340 (-6975 2875);
PAINT GREEN (-6975 2875);
DISPLAY INVISIBLE (-6975 2875);
FORCEPROP 2 LAST CDS_LIB standard
J 0
(-6650 3000);
DISPLAY INVISIBLE (-6650 3000);
FORCEADD OFFPAGE..2
R 2
(-6650 3050);
FORCEPROP 2 LAST $XR0 103 
J 0
(-6905 3050);
DISPLAY 0.638298 (-6905 3050);
PAINT MONO (-6905 3050);
FORCEPROP 2 LAST PATH I313
J 0
(-6900 3100);
DISPLAY 1.021277 (-6900 3100);
DISPLAY INVISIBLE (-6900 3100);
FORCEPROP 1 LAST COMMENT_BODY TRUE
J 2
(-6605 2955);
DISPLAY 0.872340 (-6605 2955);
PAINT GREEN (-6605 2955);
DISPLAY INVISIBLE (-6605 2955);
FORCEPROP 1 LAST OFFPAGE TRUE
J 2
(-6975 2925);
DISPLAY 0.872340 (-6975 2925);
PAINT GREEN (-6975 2925);
DISPLAY INVISIBLE (-6975 2925);
FORCEPROP 2 LAST CDS_LIB standard
J 0
(-6650 3050);
DISPLAY INVISIBLE (-6650 3050);
FORCEADD OFFPAGE..2
R 2
(-6650 2900);
FORCEPROP 2 LAST $XR0 103 
J 0
(-6905 2900);
DISPLAY 0.638298 (-6905 2900);
PAINT MONO (-6905 2900);
FORCEPROP 2 LAST PATH I314
J 0
(-6900 2950);
DISPLAY 1.021277 (-6900 2950);
DISPLAY INVISIBLE (-6900 2950);
FORCEPROP 1 LAST COMMENT_BODY TRUE
J 2
(-6605 2805);
DISPLAY 0.872340 (-6605 2805);
PAINT GREEN (-6605 2805);
DISPLAY INVISIBLE (-6605 2805);
FORCEPROP 1 LAST OFFPAGE TRUE
J 2
(-6975 2775);
DISPLAY 0.872340 (-6975 2775);
PAINT GREEN (-6975 2775);
DISPLAY INVISIBLE (-6975 2775);
FORCEPROP 2 LAST CDS_LIB standard
J 0
(-6650 2900);
DISPLAY INVISIBLE (-6650 2900);
FORCEADD OFFPAGE..2
R 2
(-6650 2850);
FORCEPROP 2 LAST $XR0 103 
J 0
(-6905 2850);
DISPLAY 0.638298 (-6905 2850);
PAINT MONO (-6905 2850);
FORCEPROP 2 LAST PATH I315
J 0
(-6900 2900);
DISPLAY 1.021277 (-6900 2900);
DISPLAY INVISIBLE (-6900 2900);
FORCEPROP 1 LAST COMMENT_BODY TRUE
J 2
(-6605 2755);
DISPLAY 0.872340 (-6605 2755);
PAINT GREEN (-6605 2755);
DISPLAY INVISIBLE (-6605 2755);
FORCEPROP 1 LAST OFFPAGE TRUE
J 2
(-6975 2725);
DISPLAY 0.872340 (-6975 2725);
PAINT GREEN (-6975 2725);
DISPLAY INVISIBLE (-6975 2725);
FORCEPROP 2 LAST CDS_LIB standard
J 0
(-6650 2850);
DISPLAY INVISIBLE (-6650 2850);
FORCEADD OFFPAGE..5
(-6650 2650);
FORCEPROP 2 LAST $XR0 103 
J 0
(-6905 2650);
DISPLAY 0.638298 (-6905 2650);
PAINT MONO (-6905 2650);
FORCEPROP 2 LAST PATH I316
J 0
(-6900 2700);
DISPLAY 1.021277 (-6900 2700);
DISPLAY INVISIBLE (-6900 2700);
FORCEPROP 1 LAST COMMENT_BODY TRUE
J 0
(-6550 2575);
DISPLAY 0.872340 (-6550 2575);
PAINT GREEN (-6550 2575);
DISPLAY INVISIBLE (-6550 2575);
FORCEPROP 1 LAST OFFPAGE TRUE
J 0
(-6325 2525);
DISPLAY 0.872340 (-6325 2525);
PAINT GREEN (-6325 2525);
DISPLAY INVISIBLE (-6325 2525);
FORCEPROP 2 LAST CDS_LIB mstr_standard
J 0
(-6650 2650);
DISPLAY INVISIBLE (-6650 2650);
FORCEADD OFFPAGE..1
(-6650 2750);
FORCEPROP 2 LAST $XR0 103 
J 0
(-6902 2750);
DISPLAY 0.638298 (-6902 2750);
PAINT MONO (-6902 2750);
FORCEPROP 2 LAST PATH I317
J 0
(-6925 2800);
DISPLAY 1.021277 (-6925 2800);
DISPLAY INVISIBLE (-6925 2800);
FORCEPROP 1 LAST COMMENT_BODY TRUE
J 0
(-6525 2650);
DISPLAY 0.872340 (-6525 2650);
PAINT GREEN (-6525 2650);
DISPLAY INVISIBLE (-6525 2650);
FORCEPROP 1 LAST OFFPAGE TRUE
J 0
(-6325 2625);
DISPLAY 0.872340 (-6325 2625);
PAINT GREEN (-6325 2625);
DISPLAY INVISIBLE (-6325 2625);
FORCEPROP 2 LAST CDS_LIB standard
J 0
(-6650 2750);
DISPLAY INVISIBLE (-6650 2750);
FORCEADD OFFPAGE..2
R 2
(-6650 2550);
FORCEPROP 2 LAST $XR0 103 
J 0
(-6905 2550);
DISPLAY 0.638298 (-6905 2550);
PAINT MONO (-6905 2550);
FORCEPROP 2 LAST PATH I318
J 0
(-6900 2600);
DISPLAY 1.021277 (-6900 2600);
DISPLAY INVISIBLE (-6900 2600);
FORCEPROP 1 LAST COMMENT_BODY TRUE
J 2
(-6605 2455);
DISPLAY 0.872340 (-6605 2455);
PAINT GREEN (-6605 2455);
DISPLAY INVISIBLE (-6605 2455);
FORCEPROP 1 LAST OFFPAGE TRUE
J 2
(-6975 2425);
DISPLAY 0.872340 (-6975 2425);
PAINT GREEN (-6975 2425);
DISPLAY INVISIBLE (-6975 2425);
FORCEPROP 2 LAST CDS_LIB standard
J 0
(-6650 2550);
DISPLAY INVISIBLE (-6650 2550);
FORCEADD OFFPAGE..2
R 2
(-6650 2500);
FORCEPROP 2 LAST $XR0 103 
J 0
(-6905 2500);
DISPLAY 0.638298 (-6905 2500);
PAINT MONO (-6905 2500);
FORCEPROP 2 LAST PATH I319
J 0
(-6900 2550);
DISPLAY 1.021277 (-6900 2550);
DISPLAY INVISIBLE (-6900 2550);
FORCEPROP 1 LAST COMMENT_BODY TRUE
J 2
(-6605 2405);
DISPLAY 0.872340 (-6605 2405);
PAINT GREEN (-6605 2405);
DISPLAY INVISIBLE (-6605 2405);
FORCEPROP 1 LAST OFFPAGE TRUE
J 2
(-6975 2375);
DISPLAY 0.872340 (-6975 2375);
PAINT GREEN (-6975 2375);
DISPLAY INVISIBLE (-6975 2375);
FORCEPROP 2 LAST CDS_LIB standard
J 0
(-6650 2500);
DISPLAY INVISIBLE (-6650 2500);
FORCEADD OFFPAGE..1
(-6650 2400);
FORCEPROP 2 LAST $XR0 103 
J 0
(-6902 2400);
DISPLAY 0.638298 (-6902 2400);
PAINT MONO (-6902 2400);
FORCEPROP 2 LAST PATH I320
J 0
(-6925 2450);
DISPLAY 1.021277 (-6925 2450);
DISPLAY INVISIBLE (-6925 2450);
FORCEPROP 1 LAST COMMENT_BODY TRUE
J 0
(-6525 2300);
DISPLAY 0.872340 (-6525 2300);
PAINT GREEN (-6525 2300);
DISPLAY INVISIBLE (-6525 2300);
FORCEPROP 1 LAST OFFPAGE TRUE
J 0
(-6325 2275);
DISPLAY 0.872340 (-6325 2275);
PAINT GREEN (-6325 2275);
DISPLAY INVISIBLE (-6325 2275);
FORCEPROP 2 LAST CDS_LIB standard
J 0
(-6650 2400);
DISPLAY INVISIBLE (-6650 2400);
FORCEADD OFFPAGE..5
(-6650 2300);
FORCEPROP 2 LAST $XR0 103 
J 0
(-6905 2300);
DISPLAY 0.638298 (-6905 2300);
PAINT MONO (-6905 2300);
FORCEPROP 2 LAST PATH I321
J 0
(-6900 2350);
DISPLAY 1.021277 (-6900 2350);
DISPLAY INVISIBLE (-6900 2350);
FORCEPROP 1 LAST COMMENT_BODY TRUE
J 0
(-6550 2225);
DISPLAY 0.872340 (-6550 2225);
PAINT GREEN (-6550 2225);
DISPLAY INVISIBLE (-6550 2225);
FORCEPROP 1 LAST OFFPAGE TRUE
J 0
(-6325 2175);
DISPLAY 0.872340 (-6325 2175);
PAINT GREEN (-6325 2175);
DISPLAY INVISIBLE (-6325 2175);
FORCEPROP 2 LAST CDS_LIB standard
J 0
(-6650 2300);
DISPLAY INVISIBLE (-6650 2300);
FORCEADD Q_RES..1
(-6725 2200);
FORCEPROP 1 LAST LOCATION R506
J 0
(-7050 2200);
DISPLAY 0.489362 (-7050 2200);
PAINT SKYBLUE (-7050 2200);
FORCEPROP 0 LAST $SEC 1
J 0
(-6900 2250);
DISPLAY 0.680851 (-6900 2250);
PAINT MONO (-6900 2250);
DISPLAY INVISIBLE (-6900 2250);
FORCEPROP 0 LAST CDS_SEC 1
J 0
(-6900 2250);
DISPLAY 1.021277 (-6900 2250);
DISPLAY INVISIBLE (-6900 2250);
FORCEPROP 1 LASTPIN (-6825 2200) $PN 1
J 0
(-6813 2212);
DISPLAY 0.489362 (-6813 2212);
PAINT MONO (-6813 2212);
FORCEPROP 1 LASTPIN (-6625 2200) $PN 2
J 0
(-6663 2212);
DISPLAY 0.489362 (-6663 2212);
PAINT MONO (-6663 2212);
FORCEPROP 1 LAST TOLERANCE 1%
J 0
(-6450 2200);
DISPLAY 0.489362 (-6450 2200);
PAINT SKYBLUE (-6450 2200);
FORCEPROP 1 LAST VALUE 15   
J 2
(-6400 2200);
DISPLAY 0.489362 (-6400 2200);
PAINT SKYBLUE (-6400 2200);
FORCEPROP 1 LAST PART_NUMBER CS01502FB11
J 0
(-6600 2175);
DISPLAY 0.489362 (-6600 2175);
PAINT SKYBLUE (-6600 2175);
FORCEPROP 1 LAST PACK_TYPE 0402LF
J 0
(-7050 2175);
DISPLAY 0.489362 (-7050 2175);
PAINT SKYBLUE (-7050 2175);
FORCEPROP 2 LAST CDS_LIB pure_quanta
J 0
(-6725 2200);
DISPLAY INVISIBLE (-6725 2200);
FORCEPROP 1 LAST PATH I322
J 0
(-6775 2350);
DISPLAY 0.978723 (-6775 2350);
PAINT WHITE (-6775 2350);
DISPLAY INVISIBLE (-6775 2350);
FORCEPROP 1 LAST WATTAGE 1/16W
J 2
(-6500 2325);
DISPLAY 0.638298 (-6500 2325);
PAINT SKYBLUE (-6500 2325);
DISPLAY INVISIBLE (-6500 2325);
FORCEPROP 1 LAST MATERIAL CHIP
J 0
(-6850 2325);
DISPLAY 0.638298 (-6850 2325);
PAINT SKYBLUE (-6850 2325);
DISPLAY INVISIBLE (-6850 2325);
FORCEADD OFFPAGE..5
(-6650 2100);
FORCEPROP 2 LAST $XR0 103 
J 0
(-6905 2100);
DISPLAY 0.638298 (-6905 2100);
PAINT MONO (-6905 2100);
FORCEPROP 2 LAST PATH I323
J 0
(-6900 2150);
DISPLAY 1.021277 (-6900 2150);
DISPLAY INVISIBLE (-6900 2150);
FORCEPROP 1 LAST COMMENT_BODY TRUE
J 0
(-6550 2025);
DISPLAY 0.872340 (-6550 2025);
PAINT GREEN (-6550 2025);
DISPLAY INVISIBLE (-6550 2025);
FORCEPROP 1 LAST OFFPAGE TRUE
J 0
(-6325 1975);
DISPLAY 0.872340 (-6325 1975);
PAINT GREEN (-6325 1975);
DISPLAY INVISIBLE (-6325 1975);
FORCEPROP 2 LAST CDS_LIB standard
J 0
(-6650 2100);
DISPLAY INVISIBLE (-6650 2100);
FORCEADD OFFPAGE..1
(-7600 2200);
FORCEPROP 2 LAST $XR0 103 
J 0
(-7852 2200);
DISPLAY 0.638298 (-7852 2200);
PAINT MONO (-7852 2200);
FORCEPROP 2 LAST PATH I324
J 0
(-7850 2250);
DISPLAY 1.021277 (-7850 2250);
DISPLAY INVISIBLE (-7850 2250);
FORCEPROP 1 LAST COMMENT_BODY TRUE
J 0
(-7475 2100);
DISPLAY 0.872340 (-7475 2100);
PAINT GREEN (-7475 2100);
DISPLAY INVISIBLE (-7475 2100);
FORCEPROP 1 LAST OFFPAGE TRUE
J 0
(-7275 2075);
DISPLAY 0.872340 (-7275 2075);
PAINT GREEN (-7275 2075);
DISPLAY INVISIBLE (-7275 2075);
FORCEPROP 2 LAST CDS_LIB mstr_standard
J 0
(-7600 2200);
DISPLAY INVISIBLE (-7600 2200);
FORCEADD CAD_NOTE..1
(-7875 2475);
FORCEPROP 0 LAST L1 R1964 PLACE CLOSE TO CPU < 25MM
J 0
(-8025 2350);
DISPLAY 0.617021 (-8025 2350);
PAINT WHITE (-8025 2350);
FORCEPROP 2 LAST CDS_LIB pure_quanta_power
J 0
(-7875 2475);
DISPLAY INVISIBLE (-7875 2475);
FORCEPROP 1 LAST COMMENT_BODY TRUE
J 0
(-7850 2575);
DISPLAY 0.574468 (-7850 2575);
PAINT WHITE (-7850 2575);
DISPLAY INVISIBLE (-7850 2575);
FORCEADD QUANTA_TITLE_BLOCK_C..1
(-100 100);
FORCEPROP 0 LAST CDS_CON_LAST_MODIFIED Fri Mar 11 14:52:32 2022
J 0
(-1985 115);
DISPLAY INVISIBLE (-1985 115);
FORCEPROP 1 LAST CUSTOM_TXT_CDS <CON_LAST_MODIFIED>
J 0
(-1985 115);
DISPLAY 0.978723 (-1985 115);
FORCEPROP 2 LAST CUSTOM_TXT_CDS <XR_PAGE_TITLE>
J 0
(-7990 5350);
DISPLAY 0.638298 (-7990 5350);
PAINT PINK (-7990 5350);
DISPLAY INVISIBLE (-7990 5350);
FORCEPROP 1 LAST CUSTOM_TXT_CDS <NAME_2>
J 0
(-3275 150);
FORCEPROP 1 LAST CUSTOM_TXT_CDS <NAME_1>
J 0
(-3275 275);
FORCEPROP 1 LAST CUSTOM_TXT_CDS <Q_NUMBER>
J 0
(-1503 203);
DISPLAY 1.212766 (-1503 203);
FORCEPROP 1 LAST CUSTOM_TXT_CDS <Q_PROJ>
J 0
(-2482 202);
DISPLAY 1.212766 (-2482 202);
FORCEPROP 1 LAST CUSTOM_TXT_CDS <Q_REV>
J 0
(-284 203);
DISPLAY 1.212766 (-284 203);
FORCEPROP 1 LAST CUSTOM_TXT_CDS <CON_PAGE_NUM> OF <CON_TOTAL_PAGES>
J 0
(-546 118);
DISPLAY 0.978723 (-546 118);
FORCEPROP 1 LAST Q_DEPT BU9
J 1
(-3863 149);
DISPLAY 1.957447 (-3863 149);
PAINT GREEN (-3863 149);
FORCEPROP 1 LAST Q_TITLE CPU1 DDR CHG
J 0
(-9375 150);
DISPLAY 2.446809 (-9375 150);
PAINT GREEN (-9375 150);
FORCEPROP 2 LAST CDS_LIB pure_quanta
J 0
(-100 100);
DISPLAY INVISIBLE (-100 100);
FORCEPROP 1 LAST CDS_LMAN_SYM_OUTLINE -9475,6775,100,-125
J 0
(-100 100);
DISPLAY 0.468085 (-100 100);
PAINT GREEN (-100 100);
DISPLAY INVISIBLE (-100 100);
FORCEPROP 2 LAST PAGE_BORDER TRUE
J 0
(-7990 5350);
DISPLAY 0.638298 (-7990 5350);
PAINT PINK (-7990 5350);
DISPLAY INVISIBLE (-7990 5350);
FORCEPROP 1 LAST COMMENT_BODY TRUE
J 0
(-88 87);
DISPLAY 0.978723 (-88 87);
PAINT GREEN (-88 87);
DISPLAY INVISIBLE (-88 87);
FORCEPROP 2 LAST CDS_XR_PAGE_TITLE CR-43 : @T6G_MB_LIB.T6G(SCH_1):PAGE43
J 0
(-7990 5350);
DISPLAY 0.638298 (-7990 5350);
PAINT PINK (-7990 5350);
DISPLAY INVISIBLE (-7990 5350);
WIRE 17 -1 (-3375 5475)(-3375 5425);
WIRE 17 -1 (-3375 5525)(-3375 5475);
WIRE 17 -1 (-3375 5425)(-3375 5375);
WIRE 17 -1 (-3375 5375)(-3375 5325);
WIRE 17 -1 (-3375 5575)(-3375 5525);
WIRE 17 -1 (-3375 5625)(-3375 5575);
WIRE 17 -1 (-3375 5325)(-3375 5275);
WIRE 17 -1 (-3375 5175)(-3375 5275);
WIRE 17 -1 (-3375 5725)(-3375 5625);
WIRE 17 -1 (-3375 5775)(-3375 5725);
WIRE 17 -1 (-3375 5125)(-3375 5175);
WIRE 17 -1 (-3375 5075)(-3375 5125);
WIRE 17 -1 (-3375 5825)(-3375 5775);
WIRE 17 -1 (-3375 5875)(-3375 5825);
WIRE 17 -1 (-3375 5025)(-3375 5075);
WIRE 17 -1 (-3375 5025)(-3375 4975);
WIRE 17 -1 (-3375 5925)(-3375 5875);
WIRE 17 -1 (-3375 5975)(-3375 5925);
WIRE 17 -1 (-3375 4975)(-3375 4925);
WIRE 17 -1 (-3375 4925)(-3375 4875);
WIRE 17 -1 (-3375 6025)(-3375 5975);
WIRE 17 -1 (-3375 6075)(-3375 6025);
WIRE 17 -1 (-3375 4875)(-3375 4825);
WIRE 17 -1 (-3375 4825)(-3375 4725);
WIRE 17 -1 (-3375 6075)(-2750 6075);
FORCEPROP 2 LAST SIG_NAME M_G_CPU1_SA_DQ<31:0>
J 2
(-2810 6085);
DISPLAY 0.489362 (-2810 6085);
WIRE 17 -1 (-3375 4725)(-3375 4675);
WIRE 17 -1 (-3375 4675)(-3375 4625);
WIRE 17 -1 (-3375 4625)(-3375 4575);
WIRE 17 -1 (-3375 4525)(-3375 4575);
WIRE 17 -1 (-3375 4475)(-3375 4525);
WIRE 17 -1 (-3375 4425)(-3375 4475);
WIRE 17 -1 (-3375 4375)(-3375 4425);
WIRE 17 -1 (-3375 4225)(-3375 4175);
WIRE 17 -1 (-3375 4275)(-3375 4225);
WIRE 17 -1 (-3375 4175)(-3375 4125);
WIRE 17 -1 (-3375 4125)(-3375 4075);
WIRE 17 -1 (-3375 4275)(-2750 4275);
FORCEPROP 2 LAST SIG_NAME M_G_CPU1_SB_DQ<31:0>
J 2
(-2810 4285);
DISPLAY 0.489362 (-2810 4285);
WIRE 17 -1 (-3375 4075)(-3375 4025);
WIRE 17 -1 (-3375 4025)(-3375 3975);
WIRE 17 -1 (-3375 3975)(-3375 3925);
WIRE 17 -1 (-3375 3925)(-3375 3825);
WIRE 17 -1 (-3375 3825)(-3375 3775);
WIRE 17 -1 (-3375 3175)(-3375 3125);
WIRE 17 -1 (-3375 3225)(-3375 3175);
WIRE 17 -1 (-3375 3125)(-3375 3075);
WIRE 17 -1 (-3375 3075)(-3375 3025);
WIRE 17 -1 (-3375 3225)(-3375 3275);
WIRE 17 -1 (-3375 3275)(-3375 3325);
WIRE 17 -1 (-3375 3025)(-3375 2925);
WIRE 17 -1 (-3375 2925)(-3375 2875);
WIRE 17 -1 (-3375 3325)(-3375 3375);
WIRE 17 -1 (-3375 3375)(-3375 3475);
WIRE 17 -1 (-3375 2875)(-3375 2825);
WIRE 17 -1 (-3375 2825)(-3375 2775);
WIRE 17 -1 (-3375 3525)(-3375 3475);
WIRE 17 -1 (-3375 3575)(-3375 3525);
WIRE 17 -1 (-3375 2725)(-3375 2775);
WIRE 17 -1 (-3375 2675)(-3375 2725);
WIRE 17 -1 (-3375 3625)(-3375 3575);
WIRE 17 -1 (-3375 3675)(-3375 3625);
WIRE 17 -1 (-3375 2625)(-3375 2675);
WIRE 17 -1 (-3375 2575)(-3375 2625);
WIRE 17 -1 (-3375 3725)(-3375 3675);
WIRE 17 -1 (-3375 3775)(-3375 3725);
WIRE 17 -1 (-3375 2375)(-3375 2425);
WIRE 17 -1 (-3375 2375)(-3375 2325);
WIRE 17 -1 (-3375 2475)(-3375 2425);
WIRE 17 -1 (-3375 2475)(-3375 2500);
WIRE 17 -1 (-3375 2275)(-3375 2325);
WIRE 17 -1 (-3375 2225)(-3375 2275);
WIRE 17 -1 (-3375 2500)(-2875 2500);
FORCEPROP 2 LAST SIG_NAME M_G_CPU1_SA_CB<7:0>
J 2
(-2875 2510);
DISPLAY 0.489362 (-2875 2510);
WIRE 17 -1 (-3375 2175)(-3375 2225);
WIRE 17 -1 (-3375 2125)(-3375 2175);
WIRE 17 -1 (-3375 2025)(-3375 1975);
WIRE 17 -1 (-3375 2025)(-3375 2050);
WIRE 17 -1 (-3375 1925)(-3375 1975);
WIRE 17 -1 (-3375 1925)(-3375 1875);
WIRE 17 -1 (-3375 2050)(-2875 2050);
FORCEPROP 2 LAST SIG_NAME M_G_CPU1_SB_CB<7:0>
J 2
(-2875 2060);
DISPLAY 0.489362 (-2875 2060);
WIRE 17 -1 (-3375 1825)(-3375 1875);
WIRE 17 -1 (-3375 1775)(-3375 1825);
WIRE 17 -1 (-3375 1725)(-3375 1775);
WIRE 17 -1 (-3375 1675)(-3375 1725);
WIRE 17 -1 (-6100 6025)(-6100 5925);
FORCEPROP 2 LAST SIG_NAME M_G_CPU1_SA_DQS_DN<9:0>
J 2
(-6135 6035);
DISPLAY 0.489362 (-6135 6035);
WIRE 17 -1 (-6100 5825)(-6100 5725);
WIRE 17 -1 (-6100 5925)(-6100 5825);
WIRE 17 -1 (-6100 5725)(-6100 5625);
WIRE 17 -1 (-6100 5525)(-6100 5625);
WIRE 17 -1 (-6100 5425)(-6100 5525);
WIRE 17 -1 (-6100 5325)(-6100 5425);
WIRE 17 -1 (-6100 5325)(-6100 5225);
WIRE 17 -1 (-5900 6075)(-5900 5975);
WIRE 17 -1 (-5900 6075)(-6700 6075);
FORCEPROP 2 LAST SIG_NAME M_G_CPU1_SA_DQS_DP<9:0>
J 2
(-6135 6085);
DISPLAY 0.489362 (-6135 6085);
WIRE 17 -1 (-6100 5225)(-6100 5125);
WIRE 17 -1 (-5900 5975)(-5900 5875);
WIRE 17 -1 (-5900 5875)(-5900 5775);
WIRE 17 -1 (-5900 5775)(-5900 5675);
WIRE 17 -1 (-5900 5575)(-5900 5675);
WIRE 17 -1 (-5900 5475)(-5900 5575);
WIRE 17 -1 (-5900 5375)(-5900 5475);
WIRE 17 -1 (-5900 5375)(-5900 5275);
WIRE 17 -1 (-5900 5275)(-5900 5175);
WIRE 17 -1 (-5900 4525)(-5900 4625);
WIRE 17 -1 (-5900 4425)(-5900 4525);
WIRE 17 -1 (-5900 4725)(-5900 4625);
WIRE 17 -1 (-5900 4825)(-5900 4725);
WIRE 17 -1 (-5900 4325)(-5900 4425);
WIRE 17 -1 (-5900 4325)(-5900 4225);
WIRE 17 -1 (-5900 4925)(-5900 4825);
WIRE 17 -1 (-5900 5025)(-5900 4925);
WIRE 17 -1 (-5900 4225)(-5900 4125);
WIRE 17 -1 (-5900 5025)(-6700 5025);
FORCEPROP 2 LAST SIG_NAME M_G_CPU1_SB_DQS_DP<9:0>
J 2
(-6135 5035);
DISPLAY 0.489362 (-6135 5035);
WIRE 17 -1 (-6100 4975)(-6100 4875);
FORCEPROP 2 LAST SIG_NAME M_G_CPU1_SB_DQS_DN<9:0>
J 2
(-6135 4985);
DISPLAY 0.489362 (-6135 4985);
WIRE 17 -1 (-6100 4775)(-6100 4675);
WIRE 17 -1 (-6100 4875)(-6100 4775);
WIRE 17 -1 (-6100 4675)(-6100 4575);
WIRE 17 -1 (-6100 4475)(-6100 4575);
WIRE 17 -1 (-6100 4375)(-6100 4475);
WIRE 17 -1 (-6100 4275)(-6100 4375);
WIRE 17 -1 (-6100 4275)(-6100 4175);
WIRE 17 -1 (-6100 4175)(-6100 4075);
WIRE 17 -1 (-6100 3875)(-6100 3925);
WIRE 17 -1 (-6100 3825)(-6100 3875);
WIRE 17 -1 (-6100 3925)(-6600 3925);
FORCEPROP 2 LAST SIG_NAME M_G_CPU1_SA_CA<6:0>
J 0
(-6600 3935);
DISPLAY 0.489362 (-6600 3935);
WIRE 17 -1 (-6100 3475)(-6100 3525);
WIRE 17 -1 (-6100 3425)(-6100 3475);
WIRE 17 -1 (-6100 3525)(-6600 3525);
FORCEPROP 2 LAST SIG_NAME M_G_CPU1_SB_CA<6:0>
J 0
(-6600 3535);
DISPLAY 0.489362 (-6600 3535);
WIRE 17 -1 (-6100 3775)(-6100 3825);
WIRE 17 -1 (-6100 3375)(-6100 3425);
WIRE 17 -1 (-6100 3725)(-6100 3775);
WIRE 17 -1 (-6100 3675)(-6100 3725);
WIRE 17 -1 (-6100 3625)(-6100 3675);
WIRE 17 -1 (-6100 3325)(-6100 3375);
WIRE 17 -1 (-6100 3275)(-6100 3325);
WIRE 17 -1 (-6100 3225)(-6100 3275);
WIRE 17 -1 (-6100 6025)(-6700 6025);
WIRE 17 -1 (-6100 4975)(-6700 4975);
WIRE 16 -1 (-7550 2200)(-6825 2200);
FORCEPROP 2 LAST SIG_NAME M_G_CPU1_ALERT_N
J 0
(-7510 2210);
DISPLAY 0.489362 (-7510 2210);
WIRE 16 -1 (-6600 1250)(-5500 1250);
FORCEPROP 2 LAST SIG_NAME TP_M_G_CPU1_SA_TEST39G
J 0
(-6585 1260);
DISPLAY 0.489362 (-6585 1260);
FORCEPROP 2 LASTPROP $XRERR UNIQUE?
J 0
(-6840 1250);
DISPLAY 0.638298 (-6840 1250);
PAINT MONO (-6840 1250);
DISPLAY INVISIBLE (-6840 1250);
WIRE 16 -1 (-6625 2200)(-5500 2200);
FORCEPROP 2 LAST SIG_NAME M_G_CPU1_ALERT_R_N
J 0
(-6335 2210);
DISPLAY 0.489362 (-6335 2210);
FORCEPROP 2 LASTPROP $XRERR UNIQUE?
J 0
(-6575 2210);
DISPLAY 0.638298 (-6575 2210);
PAINT MONO (-6575 2210);
DISPLAY INVISIBLE (-6575 2210);
WIRE 16 -1 (-6600 3000)(-5500 3000);
FORCEPROP 2 LAST SIG_NAME M_G_CPU1_CLK_DN<0>
J 0
(-6600 3010);
DISPLAY 0.489362 (-6600 3010);
WIRE 16 -1 (-6600 3050)(-5500 3050);
FORCEPROP 2 LAST SIG_NAME M_G_CPU1_CLK_DP<0>
J 0
(-6600 3060);
DISPLAY 0.489362 (-6600 3060);
WIRE 16 -1 (-6600 2900)(-5500 2900);
FORCEPROP 2 LAST SIG_NAME M_G_CPU1_SA_CS_N<0>
J 0
(-6600 2910);
DISPLAY 0.489362 (-6600 2910);
WIRE 16 -1 (-6600 2850)(-5500 2850);
FORCEPROP 2 LAST SIG_NAME M_G_CPU1_SA_CS_N<1>
J 0
(-6600 2860);
DISPLAY 0.489362 (-6600 2860);
WIRE 16 -1 (-6600 2650)(-5500 2650);
FORCEPROP 2 LAST SIG_NAME M_G_CPU1_SA_PAR
J 0
(-6600 2660);
DISPLAY 0.489362 (-6600 2660);
WIRE 16 -1 (-6600 2750)(-5500 2750);
FORCEPROP 2 LAST SIG_NAME M_G_CPU1_SA_RSP<0>
J 0
(-6600 2760);
DISPLAY 0.489362 (-6600 2760);
WIRE 16 -1 (-6600 2550)(-5500 2550);
FORCEPROP 2 LAST SIG_NAME M_G_CPU1_SB_CS_N<0>
J 0
(-6600 2560);
DISPLAY 0.489362 (-6600 2560);
WIRE 16 -1 (-6600 2500)(-5500 2500);
FORCEPROP 2 LAST SIG_NAME M_G_CPU1_SB_CS_N<1>
J 0
(-6600 2510);
DISPLAY 0.489362 (-6600 2510);
WIRE 16 -1 (-6600 2400)(-5500 2400);
FORCEPROP 2 LAST SIG_NAME M_G_CPU1_SB_RSP<0>
J 0
(-6600 2410);
DISPLAY 0.489362 (-6600 2410);
WIRE 16 -1 (-6600 2300)(-5500 2300);
FORCEPROP 2 LAST SIG_NAME M_G_CPU1_SB_PAR
J 0
(-6600 2310);
DISPLAY 0.489362 (-6600 2310);
WIRE 16 -1 (-6600 2100)(-5500 2100);
FORCEPROP 2 LAST SIG_NAME M_G_CPU1_RESET_N
J 0
(-6600 2110);
DISPLAY 0.489362 (-6600 2110);
WIRE 16 -1 (-6000 3200)(-5500 3200);
WIRE 16 -1 (-6000 3600)(-5500 3600);
WIRE 16 -1 (-6000 3250)(-5500 3250);
WIRE 16 -1 (-6000 3650)(-5500 3650);
WIRE 16 -1 (-6000 3300)(-5500 3300);
WIRE 16 -1 (-6000 3700)(-5500 3700);
WIRE 16 -1 (-6000 3350)(-5500 3350);
WIRE 16 -1 (-6000 3750)(-5500 3750);
WIRE 16 -1 (-6000 3400)(-5500 3400);
WIRE 16 -1 (-6000 3800)(-5500 3800);
WIRE 16 -1 (-6000 3450)(-5500 3450);
WIRE 16 -1 (-6000 3850)(-5500 3850);
WIRE 16 -1 (-6000 3500)(-5500 3500);
WIRE 16 -1 (-6000 3900)(-5500 3900);
WIRE 16 -1 (-6000 4050)(-5500 4050);
WIRE 16 -1 (-5800 4100)(-5500 4100);
WIRE 16 -1 (-5800 4600)(-5500 4600);
WIRE 16 -1 (-6000 4150)(-5500 4150);
WIRE 16 -1 (-5800 4700)(-5500 4700);
WIRE 16 -1 (-6000 4250)(-5500 4250);
WIRE 16 -1 (-5800 4800)(-5500 4800);
WIRE 16 -1 (-6000 4350)(-5500 4350);
WIRE 16 -1 (-5800 4900)(-5500 4900);
WIRE 16 -1 (-6000 4450)(-5500 4450);
WIRE 16 -1 (-5800 5000)(-5500 5000);
WIRE 16 -1 (-6000 4550)(-5500 4550);
WIRE 16 -1 (-6000 5100)(-5500 5100);
WIRE 16 -1 (-6000 4650)(-5500 4650);
WIRE 16 -1 (-6000 4750)(-5500 4750);
WIRE 16 -1 (-6000 4850)(-5500 4850);
WIRE 16 -1 (-6000 4950)(-5500 4950);
WIRE 16 -1 (-5800 4200)(-5500 4200);
WIRE 16 -1 (-5800 4300)(-5500 4300);
WIRE 16 -1 (-5800 4400)(-5500 4400);
WIRE 16 -1 (-5800 4500)(-5500 4500);
WIRE 16 -1 (-5800 5150)(-5500 5150);
WIRE 16 -1 (-5800 5250)(-5500 5250);
WIRE 16 -1 (-5800 5350)(-5500 5350);
WIRE 16 -1 (-5800 5450)(-5500 5450);
WIRE 16 -1 (-5800 5550)(-5500 5550);
WIRE 16 -1 (-5800 5650)(-5500 5650);
WIRE 16 -1 (-6000 5200)(-5500 5200);
WIRE 16 -1 (-5800 5750)(-5500 5750);
WIRE 16 -1 (-6000 5300)(-5500 5300);
WIRE 16 -1 (-5800 5850)(-5500 5850);
WIRE 16 -1 (-6000 5400)(-5500 5400);
WIRE 16 -1 (-5800 5950)(-5500 5950);
WIRE 16 -1 (-6000 5500)(-5500 5500);
WIRE 16 -1 (-5800 6050)(-5500 6050);
WIRE 16 -1 (-6000 5600)(-5500 5600);
WIRE 16 -1 (-6000 5700)(-5500 5700);
WIRE 16 -1 (-6000 5800)(-5500 5800);
WIRE 16 -1 (-6000 5900)(-5500 5900);
WIRE 16 -1 (-6000 6000)(-5500 6000);
WIRE 16 -1 (-3900 1650)(-3475 1650);
WIRE 16 -1 (-3900 1700)(-3475 1700);
WIRE 16 -1 (-3900 1750)(-3475 1750);
WIRE 16 -1 (-3900 1800)(-3475 1800);
WIRE 16 -1 (-3900 1850)(-3475 1850);
WIRE 16 -1 (-3900 1900)(-3475 1900);
WIRE 16 -1 (-3900 1950)(-3475 1950);
WIRE 16 -1 (-3900 2000)(-3475 2000);
WIRE 16 -1 (-3900 2400)(-3475 2400);
WIRE 16 -1 (-3900 2450)(-3475 2450);
WIRE 16 -1 (-3900 2650)(-3475 2650);
WIRE 16 -1 (-3900 2700)(-3475 2700);
WIRE 16 -1 (-3900 2750)(-3475 2750);
WIRE 16 -1 (-3900 2800)(-3475 2800);
WIRE 16 -1 (-3900 2850)(-3475 2850);
WIRE 16 -1 (-3900 2900)(-3475 2900);
WIRE 16 -1 (-3900 3000)(-3475 3000);
WIRE 16 -1 (-3900 3050)(-3475 3050);
WIRE 16 -1 (-3900 2100)(-3475 2100);
WIRE 16 -1 (-3900 2150)(-3475 2150);
WIRE 16 -1 (-3900 2550)(-3475 2550);
WIRE 16 -1 (-3900 2200)(-3475 2200);
WIRE 16 -1 (-3900 2600)(-3475 2600);
WIRE 16 -1 (-3900 2250)(-3475 2250);
WIRE 16 -1 (-3900 2300)(-3475 2300);
WIRE 16 -1 (-3900 2350)(-3475 2350);
WIRE 16 -1 (-3900 3200)(-3475 3200);
WIRE 16 -1 (-3900 3250)(-3475 3250);
WIRE 16 -1 (-3900 3300)(-3475 3300);
WIRE 16 -1 (-3900 3350)(-3475 3350);
WIRE 16 -1 (-3900 3450)(-3475 3450);
WIRE 16 -1 (-3900 3500)(-3475 3500);
WIRE 16 -1 (-3900 3750)(-3475 3750);
WIRE 16 -1 (-3900 3550)(-3475 3550);
WIRE 16 -1 (-3900 3800)(-3475 3800);
WIRE 16 -1 (-3900 3600)(-3475 3600);
WIRE 16 -1 (-3900 3900)(-3475 3900);
WIRE 16 -1 (-3900 3650)(-3475 3650);
WIRE 16 -1 (-3900 3950)(-3475 3950);
WIRE 16 -1 (-3900 3700)(-3475 3700);
WIRE 16 -1 (-3900 3100)(-3475 3100);
WIRE 16 -1 (-3900 4000)(-3475 4000);
WIRE 16 -1 (-3900 3150)(-3475 3150);
WIRE 16 -1 (-3900 4050)(-3475 4050);
WIRE 16 -1 (-3900 4900)(-3475 4900);
WIRE 16 -1 (-3900 4250)(-3475 4250);
WIRE 16 -1 (-3900 4950)(-3475 4950);
WIRE 16 -1 (-3900 4350)(-3475 4350);
WIRE 16 -1 (-3900 4400)(-3475 4400);
WIRE 16 -1 (-3900 5000)(-3475 5000);
WIRE 16 -1 (-3900 5050)(-3475 5050);
WIRE 16 -1 (-3900 4450)(-3475 4450);
WIRE 16 -1 (-3900 5100)(-3475 5100);
WIRE 16 -1 (-3900 4500)(-3475 4500);
WIRE 16 -1 (-3900 4550)(-3475 4550);
WIRE 16 -1 (-3900 4600)(-3475 4600);
WIRE 16 -1 (-3900 4650)(-3475 4650);
WIRE 16 -1 (-3900 4700)(-3475 4700);
WIRE 16 -1 (-3900 4100)(-3475 4100);
WIRE 16 -1 (-3900 4800)(-3475 4800);
WIRE 16 -1 (-3900 4150)(-3475 4150);
WIRE 16 -1 (-3900 4850)(-3475 4850);
WIRE 16 -1 (-3900 4200)(-3475 4200);
WIRE 16 -1 (-3900 6050)(-3475 6050);
WIRE 16 -1 (-3900 5500)(-3475 5500);
WIRE 16 -1 (-3900 5550)(-3475 5550);
WIRE 16 -1 (-3900 5600)(-3475 5600);
WIRE 16 -1 (-3900 5700)(-3475 5700);
WIRE 16 -1 (-3900 5750)(-3475 5750);
WIRE 16 -1 (-3900 5150)(-3475 5150);
WIRE 16 -1 (-3900 5800)(-3475 5800);
WIRE 16 -1 (-3900 5250)(-3475 5250);
WIRE 16 -1 (-3900 5850)(-3475 5850);
WIRE 16 -1 (-3900 5300)(-3475 5300);
WIRE 16 -1 (-3900 5900)(-3475 5900);
WIRE 16 -1 (-3900 5350)(-3475 5350);
WIRE 16 -1 (-3900 5950)(-3475 5950);
WIRE 16 -1 (-3900 5400)(-3475 5400);
WIRE 16 -1 (-3900 6000)(-3475 6000);
WIRE 16 -1 (-3900 5450)(-3475 5450);
QUIT
